G04 ================== begin FILE IDENTIFICATION RECORD ==================*
G04 Layout Name:  D:/<user>/Wistron_project/16315-1/gbr/16315-1.brd*
G04 Film Name:    BSILK*
G04 File Format:  Gerber RS274X*
G04 File Origin:  Cadence Allegro 16.5-S056*
G04 Origin Date:  Fri Jun 09 15:30:12 2017*
G04 *
G04 Layer:  VIA CLASS/FILMMASKBOTTOM*
G04 Layer:  REF DES/ASSEMBLY_BOTTOM*
G04 Layer:  PACKAGE GEOMETRY/SILKSCREEN_BOTTOM*
G04 Layer:  DRAWING FORMAT/LAYER_PCB_STORY*
G04 Layer:  DRAWING FORMAT/LAYER_SILK_B*
G04 Layer:  BOARD GEOMETRY/SILKSCREEN_BOTTOM*
G04 *
G04 Offset:    (0.00 0.00)*
G04 Mirror:    No*
G04 Mode:      Positive*
G04 Rotation:  0*
G04 FullContactRelief:  No*
G04 UndefLineWidth:     6.00*
G04 ================== end FILE IDENTIFICATION RECORD ====================*
%FSLAX35Y35*MOIN*%
%IR0*IPPOS*OFA0.00000B0.00000*MIA0B0*SFA1.00000B1.00000*%
%ADD10C,.026*%
%ADD11C,.02*%
%ADD12C,.012*%
%ADD13C,.015*%
%ADD14C,.016*%
%ADD15C,.006*%
%ADD16C,.008*%
G75*
%LPD*%
G75*
G36*
G01X129650Y993200D02*
Y989150D01*
X125600Y993200D01*
X129650D01*
G37*
G36*
G01X196350Y581200D02*
Y577150D01*
X192300Y581200D01*
X196350D01*
G37*
G36*
G01X419870Y135976D02*
Y59056D01*
X573070D01*
Y135976D01*
X517270D01*
Y128976D01*
X566670D01*
Y61677D01*
X427424D01*
Y128976D01*
X476270D01*
Y135976D01*
X419870D01*
G37*
G36*
G01X430717Y127276D02*
G03X428717I-1000J0D01*
G01Y124276D01*
G03X430717I1000J0D01*
G01Y127276D01*
G37*
G36*
G01X437804D02*
G03X435804I-1000J0D01*
G01Y124276D01*
G03X437804I1000J0D01*
G01Y127276D01*
G37*
G36*
G01X444891D02*
G03X442891I-1000J0D01*
G01Y124276D01*
G03X444891I1000J0D01*
G01Y127276D01*
G37*
G36*
G01X451978D02*
G03X449978I-1000J0D01*
G01Y124276D01*
G03X451978I1000J0D01*
G01Y127276D01*
G37*
G36*
G01X459065D02*
G03X457065I-1000J0D01*
G01Y124276D01*
G03X459065I1000J0D01*
G01Y127276D01*
G37*
G36*
G01X480326D02*
G03X478326I-1000J0D01*
G01Y124276D01*
G03X480326I1000J0D01*
G01Y127276D01*
G37*
G36*
G01X466152D02*
G03X464152I-1000J0D01*
G01Y124276D01*
G03X466152I1000J0D01*
G01Y127276D01*
G37*
G36*
G01X473239D02*
G03X471239I-1000J0D01*
G01Y124276D01*
G03X473239I1000J0D01*
G01Y127276D01*
G37*
G36*
G01X515761D02*
G03X513761I-1000J0D01*
G01Y124276D01*
G03X515761I1000J0D01*
G01Y127276D01*
G37*
G36*
G01X522848D02*
G03X520848I-1000J0D01*
G01Y124276D01*
G03X522848I1000J0D01*
G01Y127276D01*
G37*
G36*
G01X529935D02*
G03X527935I-1000J0D01*
G01Y124276D01*
G03X529935I1000J0D01*
G01Y127276D01*
G37*
G36*
G01X537022D02*
G03X535022I-1000J0D01*
G01Y124276D01*
G03X537022I1000J0D01*
G01Y127276D01*
G37*
G36*
G01X544109D02*
G03X542109I-1000J0D01*
G01Y124276D01*
G03X544109I1000J0D01*
G01Y127276D01*
G37*
G36*
G01X551196D02*
G03X549196I-1000J0D01*
G01Y124276D01*
G03X551196I1000J0D01*
G01Y127276D01*
G37*
G36*
G01X558283D02*
G03X556283I-1000J0D01*
G01Y124276D01*
G03X558283I1000J0D01*
G01Y127276D01*
G37*
G36*
G01X565370D02*
G03X563370I-1000J0D01*
G01Y124276D01*
G03X565370I1000J0D01*
G01Y127276D01*
G37*
G36*
G01X740782Y878602D02*
X735782D01*
X740782Y883602D01*
Y878602D01*
G37*
G36*
G01X1388374Y135976D02*
Y59056D01*
X1541574D01*
Y135976D01*
X1485774D01*
Y128976D01*
X1535174D01*
Y61677D01*
X1395928D01*
Y128976D01*
X1444774D01*
Y135976D01*
X1388374D01*
G37*
G36*
G01X1399221Y127276D02*
G03X1397221I-1000J0D01*
G01Y124276D01*
G03X1399221I1000J0D01*
G01Y127276D01*
G37*
G36*
G01X1406308D02*
G03X1404308I-1000J0D01*
G01Y124276D01*
G03X1406308I1000J0D01*
G01Y127276D01*
G37*
G36*
G01X1413395D02*
G03X1411395I-1000J0D01*
G01Y124276D01*
G03X1413395I1000J0D01*
G01Y127276D01*
G37*
G36*
G01X1420482D02*
G03X1418482I-1000J0D01*
G01Y124276D01*
G03X1420482I1000J0D01*
G01Y127276D01*
G37*
G36*
G01X1427569D02*
G03X1425569I-1000J0D01*
G01Y124276D01*
G03X1427569I1000J0D01*
G01Y127276D01*
G37*
G36*
G01X1448830D02*
G03X1446830I-1000J0D01*
G01Y124276D01*
G03X1448830I1000J0D01*
G01Y127276D01*
G37*
G36*
G01X1434656D02*
G03X1432656I-1000J0D01*
G01Y124276D01*
G03X1434656I1000J0D01*
G01Y127276D01*
G37*
G36*
G01X1441743D02*
G03X1439743I-1000J0D01*
G01Y124276D01*
G03X1441743I1000J0D01*
G01Y127276D01*
G37*
G36*
G01X1484265D02*
G03X1482265I-1000J0D01*
G01Y124276D01*
G03X1484265I1000J0D01*
G01Y127276D01*
G37*
G36*
G01X1491352D02*
G03X1489352I-1000J0D01*
G01Y124276D01*
G03X1491352I1000J0D01*
G01Y127276D01*
G37*
G36*
G01X1498439D02*
G03X1496439I-1000J0D01*
G01Y124276D01*
G03X1498439I1000J0D01*
G01Y127276D01*
G37*
G36*
G01X1505526D02*
G03X1503526I-1000J0D01*
G01Y124276D01*
G03X1505526I1000J0D01*
G01Y127276D01*
G37*
G36*
G01X1512613D02*
G03X1510613I-1000J0D01*
G01Y124276D01*
G03X1512613I1000J0D01*
G01Y127276D01*
G37*
G36*
G01X1519700D02*
G03X1517700I-1000J0D01*
G01Y124276D01*
G03X1519700I1000J0D01*
G01Y127276D01*
G37*
G36*
G01X1526787D02*
G03X1524787I-1000J0D01*
G01Y124276D01*
G03X1526787I1000J0D01*
G01Y127276D01*
G37*
G36*
G01X1533874D02*
G03X1531874I-1000J0D01*
G01Y124276D01*
G03X1533874I1000J0D01*
G01Y127276D01*
G37*
G36*
G01X1771450Y1005200D02*
Y1001150D01*
X1767400Y1005200D01*
X1771450D01*
G37*
G36*
G01X1882276Y902209D02*
X1878226D01*
X1882276Y906259D01*
Y902209D01*
G37*
G54D10*
X570779Y542831D03*
X940000Y1529200D03*
X1457200Y549600D03*
G54D11*
G01X74000Y971600D02*
X69000D01*
G01X91563Y990225D02*
Y985225D01*
G01X81800Y971600D02*
X76800D01*
G01X89600D02*
X84600D01*
G01X158263Y578225D02*
Y573225D01*
G01X140700Y559600D02*
X135700D01*
G01X148500D02*
X143500D01*
G01X156300D02*
X151300D01*
G01X199700Y981300D02*
X183100D01*
G01Y979200D02*
X199700D01*
G01X207900Y992900D02*
X202900D01*
G01X215700D02*
X210700D01*
G01X266400Y569300D02*
X249800D01*
G01Y567200D02*
X266400D01*
G01X223500Y992900D02*
X218500D01*
G01X274600Y580900D02*
X269600D01*
G01X282400D02*
X277400D01*
G01X290200D02*
X285200D01*
G01X363248Y-425196D02*
Y-505196D01*
G01D02*
X1639148D01*
G01X359248Y-409196D02*
G02I-12000J0D01*
G01X354098D02*
G02I-6850J0D01*
G01X347248Y-425196D02*
Y-393196D01*
G01X363248Y-425196D02*
X1639148D01*
G01X363248Y-460696D02*
X1639148D01*
G01X363248Y-409196D02*
X331248D01*
G01X682013Y587405D02*
X707213D01*
G01X720748Y-425196D02*
Y-505196D01*
G01X745582Y935602D02*
Y940602D01*
G01Y927802D02*
Y932802D01*
G01Y943502D02*
Y948502D01*
G01X715398Y941882D02*
X710398D01*
G01X723298D02*
X718298D01*
G01X731198D02*
X726198D01*
G01X766918Y899198D02*
X761918D01*
G01X759118D02*
X754118D01*
G01X858248Y-425196D02*
Y-505196D01*
G01X866832Y398900D02*
Y393900D01*
G01X885749Y431376D02*
Y414776D01*
G01X973248Y-425196D02*
Y-505196D01*
G01X1061158Y397074D02*
Y392074D01*
G01X1072280Y429429D02*
Y412829D01*
G01X1271648Y-425196D02*
Y-505196D01*
G01X1392850Y583800D02*
Y609000D01*
G01X1441648Y-425196D02*
Y-505196D01*
G01X1639148Y-425196D02*
Y-505196D01*
G01X1667148Y-409196D02*
G02I-12000J0D01*
G01X1661998D02*
G02I-6850J0D01*
G01X1655148Y-425196D02*
Y-393196D01*
G01X1671148Y-409196D02*
X1639148D01*
G01X1714118Y992429D02*
X1709118D01*
G01X1721918D02*
X1716918D01*
G01X1731681Y1011054D02*
Y1006054D01*
G01X1729718Y992429D02*
X1724718D01*
G01X1857817Y811035D02*
Y806035D01*
G01Y818835D02*
Y813835D01*
G01Y826635D02*
Y821635D01*
G01X1852000Y937000D02*
Y932000D01*
G01X1841500Y981600D02*
X1824900D01*
G01Y979500D02*
X1841500D01*
G01X1852000Y945000D02*
Y940000D01*
G01Y953000D02*
Y948000D01*
G01X1849700Y994300D02*
X1844700D01*
G01X1857500D02*
X1852500D01*
G01X1865300D02*
X1860300D01*
G01X1874693Y830732D02*
Y847332D01*
G01X1872593D02*
Y830732D01*
G01X1885301Y941796D02*
X1880301D01*
G01X1866500Y940000D02*
Y945000D01*
G01Y948000D02*
Y953000D01*
G54D12*
G01X45696Y882677D02*
G02I-14200J0D01*
G01X182507Y646457D02*
G02I-14200J0D01*
G01X674436D02*
G02I-14200J0D01*
G01X732310Y820866D02*
G02I-14200J0D01*
G01X1380342Y646457D02*
G02I-14200J0D01*
G01X1477192Y866929D02*
G02I-14200J0D01*
G01X1616956Y646457D02*
G02I-14200J0D01*
G01X1917546Y803937D02*
G02I-14200J0D01*
G54D13*
G01X23622Y0D02*
X54331D01*
G01Y1374803D02*
X23622D01*
G01X323229Y0D02*
X362599D01*
G01X353740Y1374803D02*
X393110D01*
G01X659474Y0D02*
X628765D01*
G01X723229Y1374803D02*
X692520D01*
G01X787402Y1626772D02*
Y1596063D01*
G01X866142Y-129134D02*
Y-98425D01*
G01X1181102Y-94488D02*
Y-125197D01*
G01X1195670Y1374803D02*
X1226378D01*
G01X1220472Y1592126D02*
Y1622835D01*
G01X1315748Y0D02*
X1346457D01*
G01X1563977Y1374803D02*
X1524607D01*
G01X1593701Y0D02*
X1633071D01*
G01X1880512D02*
X1911221D01*
G01X1895276Y1374803D02*
X1864567D01*
G54D14*
G01X859700Y466400D02*
X853000D01*
G54D15*
G01X394744Y-485863D02*
X395618Y-484988D01*
X396273Y-483530D01*
X396710Y-481487D01*
X396273Y-479738D01*
X395400Y-478571D01*
X393871Y-477696D01*
X387976D01*
Y-495196D01*
X395181D01*
X396710Y-494030D01*
X397583Y-492279D01*
X398020Y-490238D01*
X397583Y-488196D01*
X396273Y-486446D01*
X394744Y-485863D01*
X387976D01*
G01X407441Y-495196D02*
Y-483530D01*
G01Y-485863D02*
X408533Y-484696D01*
X409625Y-483821D01*
X411153Y-483530D01*
X412244Y-483821D01*
X413555Y-484696D01*
G01X423413Y-500446D02*
X424723Y-501029D01*
X426470Y-500446D01*
X427561Y-499280D01*
X428435Y-497821D01*
X429744Y-493155D01*
X432583Y-483530D01*
G01X425596D02*
X429744Y-493155D01*
G01X448991Y-484988D02*
X447463Y-483821D01*
X446153Y-483530D01*
X444406Y-484113D01*
X443096Y-485279D01*
X442223Y-487321D01*
X442004Y-489363D01*
X442223Y-491405D01*
X443096Y-493155D01*
X444406Y-494613D01*
X446153Y-495196D01*
X447681Y-494613D01*
X448991Y-493446D01*
G01X459723Y-487321D02*
X466710D01*
X466055Y-485279D01*
X464963Y-484113D01*
X463435Y-483530D01*
X461906Y-483821D01*
X460596Y-484696D01*
X459723Y-486738D01*
X459286Y-488488D01*
Y-490238D01*
X459723Y-491988D01*
X460815Y-493738D01*
X462125Y-494904D01*
X463653Y-495196D01*
X465181Y-494613D01*
X466710Y-492863D01*
G01X502801Y-479155D02*
X501491Y-478279D01*
X499963Y-477696D01*
X498216D01*
X496251Y-478571D01*
X494723Y-480029D01*
X493631Y-481780D01*
X492758Y-484696D01*
X492539Y-487321D01*
X492976Y-489946D01*
X493631Y-491696D01*
X494941Y-493446D01*
X496470Y-494613D01*
X497998Y-495196D01*
X499526D01*
X501055Y-494613D01*
X502365Y-493738D01*
X503457Y-492572D01*
G01X519428Y-495196D02*
Y-483530D01*
G01Y-485571D02*
X518555Y-484405D01*
X517244Y-483821D01*
X515716Y-483530D01*
X514188Y-484113D01*
X512878Y-485279D01*
X512004Y-487029D01*
X511568Y-489363D01*
X512004Y-491696D01*
X512878Y-493446D01*
X514188Y-494613D01*
X515716Y-495196D01*
X517244Y-494904D01*
X518555Y-494030D01*
X519428Y-492863D01*
G01X529286Y-495196D02*
Y-483530D01*
G01Y-486446D02*
X530160Y-484988D01*
X531470Y-483821D01*
X533216Y-483530D01*
X534744Y-483821D01*
X536055Y-484988D01*
X536710Y-487029D01*
Y-495196D01*
G01X545913Y-500446D02*
X547223Y-501029D01*
X548970Y-500446D01*
X550061Y-499280D01*
X550935Y-497821D01*
X552244Y-493155D01*
X555083Y-483530D01*
G01X548096D02*
X552244Y-493155D01*
G01X567998Y-495196D02*
X566688Y-494904D01*
X565378Y-493738D01*
X564504Y-491696D01*
X564068Y-489363D01*
X564504Y-487029D01*
X565378Y-484988D01*
X566688Y-483821D01*
X567998Y-483530D01*
X569308Y-483821D01*
X570618Y-484988D01*
X571491Y-487029D01*
X571710Y-489363D01*
X571491Y-491696D01*
X570618Y-493738D01*
X569308Y-494904D01*
X567998Y-495196D01*
G01X581786D02*
Y-483530D01*
G01Y-486446D02*
X582660Y-484988D01*
X583970Y-483821D01*
X585716Y-483530D01*
X587244Y-483821D01*
X588555Y-484988D01*
X589210Y-487029D01*
Y-495196D01*
G01X616350D02*
Y-477696D01*
X624646D01*
G01X621590Y-486154D02*
X616350D01*
G01X637998Y-495779D02*
X637561Y-495488D01*
Y-494904D01*
X637998Y-494613D01*
X638435Y-494904D01*
Y-495488D01*
X637998Y-495779D01*
G01X650695Y-495196D02*
Y-477696D01*
X655061D01*
X656808Y-478571D01*
X658118Y-479738D01*
X659210Y-481487D01*
X660083Y-483530D01*
X660301Y-486446D01*
X660083Y-489363D01*
X659210Y-491405D01*
X658118Y-493155D01*
X656808Y-494321D01*
X655061Y-495196D01*
X650695D01*
G01X668631D02*
Y-477696D01*
X673871D01*
X675618Y-478571D01*
X676928Y-480613D01*
X677365Y-482946D01*
X676928Y-485279D01*
X675836Y-487029D01*
X673871Y-487905D01*
X668631D01*
G01X692244Y-485863D02*
X693118Y-484988D01*
X693773Y-483530D01*
X694210Y-481487D01*
X693773Y-479738D01*
X692900Y-478571D01*
X691371Y-477696D01*
X685476D01*
Y-495196D01*
X692681D01*
X694210Y-494030D01*
X695083Y-492279D01*
X695520Y-490238D01*
X695083Y-488196D01*
X693773Y-486446D01*
X692244Y-485863D01*
X685476D01*
G01X501071Y-450196D02*
Y-432696D01*
X506748Y-447279D01*
X512425Y-432696D01*
Y-450196D01*
G01X524248D02*
X522938Y-449904D01*
X521628Y-448738D01*
X520754Y-446696D01*
X520318Y-444363D01*
X520754Y-442029D01*
X521628Y-439988D01*
X522938Y-438821D01*
X524248Y-438530D01*
X525558Y-438821D01*
X526868Y-439988D01*
X527741Y-442029D01*
X527960Y-444363D01*
X527741Y-446696D01*
X526868Y-448738D01*
X525558Y-449904D01*
X524248Y-450196D01*
G01X545678Y-432696D02*
Y-450196D01*
G01Y-447572D02*
X544805Y-449030D01*
X543494Y-449904D01*
X541966Y-450196D01*
X540220Y-449613D01*
X538910Y-448155D01*
X538036Y-446405D01*
X537818Y-444363D01*
X538036Y-442321D01*
X538910Y-440571D01*
X540220Y-439113D01*
X541966Y-438530D01*
X543494Y-438821D01*
X544586Y-439405D01*
X545678Y-440571D01*
G01X555973Y-442321D02*
X562960D01*
X562305Y-440279D01*
X561213Y-439113D01*
X559685Y-438530D01*
X558156Y-438821D01*
X556846Y-439696D01*
X555973Y-441738D01*
X555536Y-443488D01*
Y-445238D01*
X555973Y-446988D01*
X557065Y-448738D01*
X558375Y-449904D01*
X559903Y-450196D01*
X561431Y-449613D01*
X562960Y-447863D01*
G01X576748Y-450196D02*
Y-432696D01*
G01X754448Y-495196D02*
Y-477696D01*
X751828Y-481196D01*
G01Y-495196D02*
X757068D01*
G01X767800Y-487905D02*
X769328Y-485863D01*
X770638Y-484696D01*
X772385Y-484113D01*
X773913Y-484696D01*
X775005Y-485863D01*
X775878Y-487613D01*
X776096Y-489654D01*
X775878Y-491405D01*
X775005Y-493155D01*
X773694Y-494613D01*
X772166Y-495196D01*
X770420Y-494613D01*
X768891Y-492863D01*
X768018Y-490238D01*
X767800Y-487321D01*
X768236Y-483530D01*
X768891Y-481487D01*
X769983Y-479446D01*
X771511Y-477988D01*
X773040Y-477696D01*
X774568Y-478279D01*
X775660Y-479738D01*
G01X784645Y-491696D02*
X785954Y-493738D01*
X787701Y-494904D01*
X789666Y-495196D01*
X791413Y-494904D01*
X793160Y-493446D01*
X794251Y-491696D01*
X794470Y-489946D01*
X794033Y-487905D01*
X792505Y-486446D01*
X790976Y-485863D01*
X789011D01*
G01X790976D02*
X792286Y-484988D01*
X793378Y-483530D01*
X793815Y-481780D01*
X793378Y-480029D01*
X792286Y-478571D01*
X790321Y-477696D01*
X788356Y-477988D01*
X786391Y-479155D01*
G01X806948Y-495196D02*
Y-477696D01*
X804328Y-481196D01*
G01Y-495196D02*
X809568D01*
G01X819645Y-492572D02*
X820954Y-494030D01*
X822483Y-494904D01*
X824448Y-495196D01*
X826413Y-494613D01*
X827941Y-493446D01*
X829033Y-491405D01*
X829251Y-489071D01*
X828815Y-486738D01*
X827723Y-485279D01*
X826194Y-484113D01*
X824666Y-483821D01*
X823138Y-484113D01*
X821173Y-485279D01*
X821828Y-477696D01*
X827723D01*
G01X741331Y-450196D02*
Y-432696D01*
X746571D01*
X748318Y-433571D01*
X749628Y-435613D01*
X750065Y-437946D01*
X749628Y-440279D01*
X748536Y-442029D01*
X746571Y-442905D01*
X741331D01*
G01X768001Y-434155D02*
X766691Y-433279D01*
X765163Y-432696D01*
X763416D01*
X761451Y-433571D01*
X759923Y-435029D01*
X758831Y-436780D01*
X757958Y-439696D01*
X757739Y-442321D01*
X758176Y-444946D01*
X758831Y-446696D01*
X760141Y-448446D01*
X761670Y-449613D01*
X763198Y-450196D01*
X764726D01*
X766255Y-449613D01*
X767565Y-448738D01*
X768657Y-447572D01*
G01X782444Y-440863D02*
X783318Y-439988D01*
X783973Y-438530D01*
X784410Y-436487D01*
X783973Y-434738D01*
X783100Y-433571D01*
X781571Y-432696D01*
X775676D01*
Y-450196D01*
X782881D01*
X784410Y-449030D01*
X785283Y-447279D01*
X785720Y-445238D01*
X785283Y-443196D01*
X783973Y-441446D01*
X782444Y-440863D01*
X775676D01*
G01X791648Y-456029D02*
X804748D01*
G01X810676Y-450196D02*
Y-432696D01*
X820720Y-450196D01*
Y-432696D01*
G01X833198Y-450196D02*
X831451Y-449904D01*
X829923Y-448738D01*
X828613Y-446988D01*
X827739Y-444946D01*
X827303Y-442613D01*
Y-440279D01*
X827739Y-437946D01*
X828613Y-435904D01*
X829923Y-434155D01*
X831451Y-432988D01*
X833198Y-432696D01*
X834944Y-432988D01*
X836473Y-434155D01*
X837783Y-435904D01*
X838657Y-437946D01*
X839093Y-440279D01*
Y-442613D01*
X838657Y-444946D01*
X837783Y-446988D01*
X836473Y-448738D01*
X834944Y-449904D01*
X833198Y-450196D01*
G01X884039Y-432696D02*
X889498Y-450196D01*
X894957Y-432696D01*
G01X911365Y-450196D02*
X902631D01*
Y-432696D01*
X911365D01*
G01X907871Y-441154D02*
X902631D01*
G01X920131Y-450196D02*
Y-432696D01*
X925590D01*
X927336Y-433571D01*
X928428Y-434738D01*
X928865Y-437071D01*
X928428Y-439405D01*
X927118Y-440863D01*
X925590Y-441738D01*
X920131D01*
G01X925590D02*
X928865Y-450196D01*
G01X941998Y-450779D02*
X941561Y-450488D01*
Y-449904D01*
X941998Y-449613D01*
X942435Y-449904D01*
Y-450488D01*
X941998Y-450779D01*
G01X915748Y-495196D02*
Y-477696D01*
X913128Y-481196D01*
G01Y-495196D02*
X918368D01*
G01X1155602Y-485863D02*
X1154728Y-484988D01*
X1154073Y-483530D01*
X1153636Y-481487D01*
X1154073Y-479738D01*
X1154946Y-478571D01*
X1156475Y-477696D01*
X1162370D01*
Y-495196D01*
X1155165D01*
X1153636Y-494030D01*
X1152763Y-492279D01*
X1152326Y-490238D01*
X1152763Y-488196D01*
X1154073Y-486446D01*
X1155602Y-485863D01*
X1162370D01*
G01X1144433Y-492863D02*
X1142686Y-494321D01*
X1140721Y-495196D01*
X1138975D01*
X1137228Y-494321D01*
X1135918Y-492863D01*
X1135263Y-490821D01*
X1135700Y-488780D01*
X1136791Y-487029D01*
X1138756Y-485863D01*
X1141376Y-485279D01*
X1142905Y-484113D01*
X1143560Y-482071D01*
X1143123Y-480029D01*
X1142031Y-478571D01*
X1140503Y-477696D01*
X1138975D01*
X1137446Y-478279D01*
X1136136Y-479738D01*
G01X1124968Y-477696D02*
X1119728D01*
G01X1122348D02*
Y-495196D01*
G01X1124968D02*
X1119728D01*
G01X1109215Y-477696D02*
Y-495196D01*
X1100481D01*
G01X1092151D02*
Y-477696D01*
G01X1083855D02*
X1092151Y-488488D01*
G01X1082545Y-495196D02*
X1088440Y-483530D01*
G01X1082981Y-432696D02*
Y-450196D01*
X1091715D01*
G01X1108778D02*
Y-438530D01*
G01Y-440571D02*
X1107905Y-439405D01*
X1106594Y-438821D01*
X1105066Y-438530D01*
X1103538Y-439113D01*
X1102228Y-440279D01*
X1101354Y-442029D01*
X1100918Y-444363D01*
X1101354Y-446696D01*
X1102228Y-448446D01*
X1103538Y-449613D01*
X1105066Y-450196D01*
X1106594Y-449904D01*
X1107905Y-449030D01*
X1108778Y-447863D01*
G01X1117763Y-455446D02*
X1119073Y-456029D01*
X1120820Y-455446D01*
X1121911Y-454280D01*
X1122785Y-452821D01*
X1124094Y-448155D01*
X1126933Y-438530D01*
G01X1119946D02*
X1124094Y-448155D01*
G01X1136573Y-442321D02*
X1143560D01*
X1142905Y-440279D01*
X1141813Y-439113D01*
X1140285Y-438530D01*
X1138756Y-438821D01*
X1137446Y-439696D01*
X1136573Y-441738D01*
X1136136Y-443488D01*
Y-445238D01*
X1136573Y-446988D01*
X1137665Y-448738D01*
X1138975Y-449904D01*
X1140503Y-450196D01*
X1142031Y-449613D01*
X1143560Y-447863D01*
G01X1154291Y-450196D02*
Y-438530D01*
G01Y-440863D02*
X1155383Y-439696D01*
X1156475Y-438821D01*
X1158003Y-438530D01*
X1159094Y-438821D01*
X1160405Y-439696D01*
G01X1312898Y-495196D02*
X1311151Y-494904D01*
X1309623Y-493738D01*
X1308313Y-491988D01*
X1307439Y-489946D01*
X1307003Y-487613D01*
Y-485279D01*
X1307439Y-482946D01*
X1308313Y-480904D01*
X1309623Y-479155D01*
X1311151Y-477988D01*
X1312898Y-477696D01*
X1314644Y-477988D01*
X1316173Y-479155D01*
X1317483Y-480904D01*
X1318357Y-482946D01*
X1318793Y-485279D01*
Y-487613D01*
X1318357Y-489946D01*
X1317483Y-491988D01*
X1316173Y-493738D01*
X1314644Y-494904D01*
X1312898Y-495196D01*
G01X1314644Y-490529D02*
X1317265Y-495196D01*
G01X1325595Y-477696D02*
Y-490238D01*
X1326468Y-492863D01*
X1328215Y-494613D01*
X1330398Y-495196D01*
X1332581Y-494613D01*
X1334328Y-492863D01*
X1335201Y-490238D01*
Y-477696D01*
G01X1345278D02*
X1350518D01*
G01X1347898D02*
Y-495196D01*
G01X1345278D02*
X1350518D01*
G01X1360376D02*
Y-477696D01*
X1370420Y-495196D01*
Y-477696D01*
G01X1387701Y-479155D02*
X1386391Y-478279D01*
X1384863Y-477696D01*
X1383116D01*
X1381151Y-478571D01*
X1379623Y-480029D01*
X1378531Y-481780D01*
X1377658Y-484696D01*
X1377439Y-487321D01*
X1377876Y-489946D01*
X1378531Y-491696D01*
X1379841Y-493446D01*
X1381370Y-494613D01*
X1382898Y-495196D01*
X1384426D01*
X1385955Y-494613D01*
X1387265Y-493738D01*
X1388357Y-492572D01*
G01X1400398Y-495196D02*
Y-487321D01*
X1396031Y-477696D01*
G01X1404765D02*
X1400398Y-487321D01*
G01X1290595Y-450196D02*
Y-432696D01*
X1294961D01*
X1296708Y-433571D01*
X1298018Y-434738D01*
X1299110Y-436487D01*
X1299983Y-438530D01*
X1300201Y-441446D01*
X1299983Y-444363D01*
X1299110Y-446405D01*
X1298018Y-448155D01*
X1296708Y-449321D01*
X1294961Y-450196D01*
X1290595D01*
G01X1309623Y-442321D02*
X1316610D01*
X1315955Y-440279D01*
X1314863Y-439113D01*
X1313335Y-438530D01*
X1311806Y-438821D01*
X1310496Y-439696D01*
X1309623Y-441738D01*
X1309186Y-443488D01*
Y-445238D01*
X1309623Y-446988D01*
X1310715Y-448738D01*
X1312025Y-449904D01*
X1313553Y-450196D01*
X1315081Y-449613D01*
X1316610Y-447863D01*
G01X1327123Y-448155D02*
X1328215Y-449321D01*
X1329743Y-450196D01*
X1331053D01*
X1332363Y-449613D01*
X1333236Y-448738D01*
X1333673Y-447572D01*
X1333455Y-445821D01*
X1332581Y-444946D01*
X1328651Y-443196D01*
X1327778Y-441154D01*
X1328215Y-439696D01*
X1329088Y-438821D01*
X1330398Y-438530D01*
X1331708Y-438821D01*
X1333018Y-439696D01*
G01X1347898Y-438530D02*
Y-450196D01*
G01Y-433863D02*
X1347461Y-433571D01*
Y-432988D01*
X1347898Y-432696D01*
X1348335Y-432988D01*
Y-433571D01*
X1347898Y-433863D01*
G01X1362341Y-454571D02*
X1363870Y-455738D01*
X1365616Y-456029D01*
X1367144Y-455738D01*
X1368455Y-454280D01*
X1369328Y-452238D01*
Y-438530D01*
G01Y-440863D02*
X1368455Y-439696D01*
X1367144Y-438821D01*
X1365616Y-438530D01*
X1363870Y-439113D01*
X1362778Y-440279D01*
X1361904Y-442321D01*
X1361468Y-444363D01*
X1361686Y-446113D01*
X1362560Y-448155D01*
X1363870Y-449613D01*
X1365616Y-450196D01*
X1366926Y-449904D01*
X1368455Y-448738D01*
X1369328Y-447572D01*
G01X1379186Y-450196D02*
Y-438530D01*
G01Y-441446D02*
X1380060Y-439988D01*
X1381370Y-438821D01*
X1383116Y-438530D01*
X1384644Y-438821D01*
X1385955Y-439988D01*
X1386610Y-442029D01*
Y-450196D01*
G01X1397123Y-442321D02*
X1404110D01*
X1403455Y-440279D01*
X1402363Y-439113D01*
X1400835Y-438530D01*
X1399306Y-438821D01*
X1397996Y-439696D01*
X1397123Y-441738D01*
X1396686Y-443488D01*
Y-445238D01*
X1397123Y-446988D01*
X1398215Y-448738D01*
X1399525Y-449904D01*
X1401053Y-450196D01*
X1402581Y-449613D01*
X1404110Y-447863D01*
G01X1414841Y-450196D02*
Y-438530D01*
G01Y-440863D02*
X1415933Y-439696D01*
X1417025Y-438821D01*
X1418553Y-438530D01*
X1419644Y-438821D01*
X1420955Y-439696D01*
G01X1461598Y-477696D02*
X1459851Y-478279D01*
X1458541Y-479738D01*
X1457668Y-481487D01*
X1457013Y-483821D01*
X1456795Y-486446D01*
X1457013Y-489071D01*
X1457668Y-491405D01*
X1458541Y-493155D01*
X1459851Y-494613D01*
X1461598Y-495196D01*
X1463344Y-494613D01*
X1464655Y-493155D01*
X1465528Y-491405D01*
X1466183Y-489071D01*
X1466401Y-486446D01*
X1466183Y-483821D01*
X1465528Y-481487D01*
X1464655Y-479738D01*
X1463344Y-478279D01*
X1461598Y-477696D01*
G01X1474950Y-487905D02*
X1476478Y-485863D01*
X1477788Y-484696D01*
X1479535Y-484113D01*
X1481063Y-484696D01*
X1482155Y-485863D01*
X1483028Y-487613D01*
X1483246Y-489654D01*
X1483028Y-491405D01*
X1482155Y-493155D01*
X1480844Y-494613D01*
X1479316Y-495196D01*
X1477570Y-494613D01*
X1476041Y-492863D01*
X1475168Y-490238D01*
X1474950Y-487321D01*
X1475386Y-483530D01*
X1476041Y-481487D01*
X1477133Y-479446D01*
X1478661Y-477988D01*
X1480190Y-477696D01*
X1481718Y-478279D01*
X1482810Y-479738D01*
G01X1492668Y-495779D02*
X1500528Y-477696D01*
G01X1514098D02*
X1512351Y-478279D01*
X1511041Y-479738D01*
X1510168Y-481487D01*
X1509513Y-483821D01*
X1509295Y-486446D01*
X1509513Y-489071D01*
X1510168Y-491405D01*
X1511041Y-493155D01*
X1512351Y-494613D01*
X1514098Y-495196D01*
X1515844Y-494613D01*
X1517155Y-493155D01*
X1518028Y-491405D01*
X1518683Y-489071D01*
X1518901Y-486446D01*
X1518683Y-483821D01*
X1518028Y-481487D01*
X1517155Y-479738D01*
X1515844Y-478279D01*
X1514098Y-477696D01*
G01X1527886Y-493155D02*
X1529415Y-494613D01*
X1531161Y-495196D01*
X1532908Y-494613D01*
X1534436Y-492863D01*
X1535528Y-490238D01*
X1535965Y-487613D01*
Y-484405D01*
X1535528Y-481780D01*
X1534436Y-479446D01*
X1533126Y-478279D01*
X1531598Y-477696D01*
X1529851Y-478279D01*
X1528541Y-479446D01*
X1527668Y-481196D01*
X1527231Y-483530D01*
X1527668Y-485571D01*
X1528760Y-487613D01*
X1530070Y-488780D01*
X1531598Y-489071D01*
X1533344Y-488488D01*
X1534655Y-487029D01*
X1535965Y-484405D01*
G01X1545168Y-495779D02*
X1553028Y-477696D01*
G01X1562450Y-480613D02*
X1563760Y-478863D01*
X1565288Y-477988D01*
X1567035Y-477696D01*
X1569218Y-478279D01*
X1570746Y-479738D01*
X1571183Y-481487D01*
X1570965Y-483238D01*
X1570091Y-484696D01*
X1565725Y-487613D01*
X1563760Y-489654D01*
X1562450Y-492572D01*
X1562013Y-495196D01*
X1571183D01*
G01X1584098Y-477696D02*
X1582351Y-478279D01*
X1581041Y-479738D01*
X1580168Y-481487D01*
X1579513Y-483821D01*
X1579295Y-486446D01*
X1579513Y-489071D01*
X1580168Y-491405D01*
X1581041Y-493155D01*
X1582351Y-494613D01*
X1584098Y-495196D01*
X1585844Y-494613D01*
X1587155Y-493155D01*
X1588028Y-491405D01*
X1588683Y-489071D01*
X1588901Y-486446D01*
X1588683Y-483821D01*
X1588028Y-481487D01*
X1587155Y-479738D01*
X1585844Y-478279D01*
X1584098Y-477696D01*
G01X1601598Y-495196D02*
Y-477696D01*
X1598978Y-481196D01*
G01Y-495196D02*
X1604218D01*
G01X1618661D02*
X1619098Y-491405D01*
X1619753Y-488196D01*
X1620626Y-485279D01*
X1621718Y-482071D01*
X1623465Y-477696D01*
X1614731D01*
G01X1509295Y-450196D02*
Y-432696D01*
X1513661D01*
X1515408Y-433571D01*
X1516718Y-434738D01*
X1517810Y-436487D01*
X1518683Y-438530D01*
X1518901Y-441446D01*
X1518683Y-444363D01*
X1517810Y-446405D01*
X1516718Y-448155D01*
X1515408Y-449321D01*
X1513661Y-450196D01*
X1509295D01*
G01X1535528D02*
Y-438530D01*
G01Y-440571D02*
X1534655Y-439405D01*
X1533344Y-438821D01*
X1531816Y-438530D01*
X1530288Y-439113D01*
X1528978Y-440279D01*
X1528104Y-442029D01*
X1527668Y-444363D01*
X1528104Y-446696D01*
X1528978Y-448446D01*
X1530288Y-449613D01*
X1531816Y-450196D01*
X1533344Y-449904D01*
X1534655Y-449030D01*
X1535528Y-447863D01*
G01X1549098Y-432696D02*
Y-450196D01*
G01X1546041Y-438530D02*
X1552155D01*
G01X1563323Y-442321D02*
X1570310D01*
X1569655Y-440279D01*
X1568563Y-439113D01*
X1567035Y-438530D01*
X1565506Y-438821D01*
X1564196Y-439696D01*
X1563323Y-441738D01*
X1562886Y-443488D01*
Y-445238D01*
X1563323Y-446988D01*
X1564415Y-448738D01*
X1565725Y-449904D01*
X1567253Y-450196D01*
X1568781Y-449613D01*
X1570310Y-447863D01*
G01X35512Y901723D02*
Y904223D01*
X33596Y901723D01*
Y904223D01*
G01X32371D02*
Y902431D01*
X32204Y902056D01*
X31871Y901806D01*
X31454Y901723D01*
X31037Y901806D01*
X30704Y902056D01*
X30537Y902431D01*
Y904223D01*
G01X28354D02*
Y901723D01*
G01X29312Y904223D02*
X27396D01*
G01X25254Y901723D02*
Y904223D01*
X25754Y903723D01*
G01Y901723D02*
X24754D01*
G01X58500Y965617D02*
X56000D01*
Y967283D01*
G01Y969550D02*
X58500D01*
X58000Y969050D01*
G01X56000D02*
Y970050D01*
G01X59900Y965000D02*
Y978400D01*
G01X67100Y965000D02*
X59900D01*
G01X67100Y978400D02*
Y965000D01*
G01X59900Y978400D02*
X67100D01*
G01X57500Y984467D02*
X60000D01*
Y985508D01*
X59875Y985842D01*
X59708Y986050D01*
X59375Y986133D01*
X59042Y986050D01*
X58833Y985800D01*
X58708Y985508D01*
Y984467D01*
G01Y985508D02*
X57500Y986133D01*
G01Y988400D02*
X60000D01*
X59500Y987900D01*
G01X57500D02*
Y988900D01*
G01X59583Y990708D02*
X59833Y990958D01*
X59958Y991250D01*
X60000Y991583D01*
X59917Y992000D01*
X59708Y992292D01*
X59458Y992375D01*
X59208Y992333D01*
X59000Y992167D01*
X58583Y991333D01*
X58292Y990958D01*
X57875Y990708D01*
X57500Y990625D01*
Y992375D01*
G01X60000Y994600D02*
X59917Y994267D01*
X59708Y994017D01*
X59458Y993850D01*
X59125Y993725D01*
X58750Y993683D01*
X58375Y993725D01*
X58042Y993850D01*
X57792Y994017D01*
X57583Y994267D01*
X57500Y994600D01*
X57583Y994933D01*
X57792Y995183D01*
X58042Y995350D01*
X58375Y995475D01*
X58750Y995517D01*
X59125Y995475D01*
X59458Y995350D01*
X59708Y995183D01*
X59917Y994933D01*
X60000Y994600D01*
G01X58542Y996908D02*
X58833Y997200D01*
X59000Y997450D01*
X59083Y997783D01*
X59000Y998075D01*
X58833Y998283D01*
X58583Y998450D01*
X58292Y998492D01*
X58042Y998450D01*
X57792Y998283D01*
X57583Y998033D01*
X57500Y997742D01*
X57583Y997408D01*
X57833Y997117D01*
X58208Y996950D01*
X58625Y996908D01*
X59167Y996992D01*
X59458Y997117D01*
X59750Y997325D01*
X59958Y997617D01*
X60000Y997908D01*
X59917Y998200D01*
X59708Y998408D01*
G01X118517Y963500D02*
Y961708D01*
X118350Y961333D01*
X118017Y961083D01*
X117600Y961000D01*
X117183Y961083D01*
X116850Y961333D01*
X116683Y961708D01*
Y963500D01*
G01X115292Y963083D02*
X115042Y963333D01*
X114750Y963458D01*
X114417Y963500D01*
X114000Y963417D01*
X113708Y963208D01*
X113625Y962958D01*
X113667Y962708D01*
X113833Y962500D01*
X114667Y962083D01*
X115042Y961792D01*
X115292Y961375D01*
X115375Y961000D01*
X113625D01*
G01X111400Y963500D02*
X111733Y963417D01*
X111983Y963208D01*
X112150Y962958D01*
X112275Y962625D01*
X112317Y962250D01*
X112275Y961875D01*
X112150Y961542D01*
X111983Y961292D01*
X111733Y961083D01*
X111400Y961000D01*
X111067Y961083D01*
X110817Y961292D01*
X110650Y961542D01*
X110525Y961875D01*
X110483Y962250D01*
X110525Y962625D01*
X110650Y962958D01*
X110817Y963208D01*
X111067Y963417D01*
X111400Y963500D01*
G01X106950Y965200D02*
X101950D01*
Y970200D01*
G01X102957Y985106D02*
X99957D01*
G01X102957Y975263D02*
X100957D01*
G01X77292Y952767D02*
X77417Y952517D01*
X77500Y952225D01*
Y951892D01*
X77375Y951517D01*
X77167Y951225D01*
X76917Y951017D01*
X76500Y950850D01*
X76125Y950808D01*
X75750Y950892D01*
X75500Y951017D01*
X75250Y951267D01*
X75083Y951558D01*
X75000Y951850D01*
Y952142D01*
X75083Y952433D01*
X75208Y952683D01*
X75375Y952892D01*
G01X76042Y954158D02*
X76333Y954450D01*
X76500Y954700D01*
X76583Y955033D01*
X76500Y955325D01*
X76333Y955533D01*
X76083Y955700D01*
X75792Y955742D01*
X75542Y955700D01*
X75292Y955533D01*
X75083Y955283D01*
X75000Y954992D01*
X75083Y954658D01*
X75333Y954367D01*
X75708Y954200D01*
X76125Y954158D01*
X76667Y954242D01*
X76958Y954367D01*
X77250Y954575D01*
X77458Y954867D01*
X77500Y955158D01*
X77417Y955450D01*
X77208Y955658D01*
G01X77500Y958050D02*
X77417Y957717D01*
X77208Y957467D01*
X76958Y957300D01*
X76625Y957175D01*
X76250Y957133D01*
X75875Y957175D01*
X75542Y957300D01*
X75292Y957467D01*
X75083Y957717D01*
X75000Y958050D01*
X75083Y958383D01*
X75292Y958633D01*
X75542Y958800D01*
X75875Y958925D01*
X76250Y958967D01*
X76625Y958925D01*
X76958Y958800D01*
X77208Y958633D01*
X77417Y958383D01*
X77500Y958050D01*
G01X77083Y960358D02*
X77333Y960608D01*
X77458Y960900D01*
X77500Y961233D01*
X77417Y961650D01*
X77208Y961942D01*
X76958Y962025D01*
X76708Y961983D01*
X76500Y961817D01*
X76083Y960983D01*
X75792Y960608D01*
X75375Y960358D01*
X75000Y960275D01*
Y962025D01*
G01X81792Y952767D02*
X81917Y952517D01*
X82000Y952225D01*
Y951892D01*
X81875Y951517D01*
X81667Y951225D01*
X81417Y951017D01*
X81000Y950850D01*
X80625Y950808D01*
X80250Y950892D01*
X80000Y951017D01*
X79750Y951267D01*
X79583Y951558D01*
X79500Y951850D01*
Y952142D01*
X79583Y952433D01*
X79708Y952683D01*
X79875Y952892D01*
G01X80542Y954158D02*
X80833Y954450D01*
X81000Y954700D01*
X81083Y955033D01*
X81000Y955325D01*
X80833Y955533D01*
X80583Y955700D01*
X80292Y955742D01*
X80042Y955700D01*
X79792Y955533D01*
X79583Y955283D01*
X79500Y954992D01*
X79583Y954658D01*
X79833Y954367D01*
X80208Y954200D01*
X80625Y954158D01*
X81167Y954242D01*
X81458Y954367D01*
X81750Y954575D01*
X81958Y954867D01*
X82000Y955158D01*
X81917Y955450D01*
X81708Y955658D01*
G01X82000Y958050D02*
X81917Y957717D01*
X81708Y957467D01*
X81458Y957300D01*
X81125Y957175D01*
X80750Y957133D01*
X80375Y957175D01*
X80042Y957300D01*
X79792Y957467D01*
X79583Y957717D01*
X79500Y958050D01*
X79583Y958383D01*
X79792Y958633D01*
X80042Y958800D01*
X80375Y958925D01*
X80750Y958967D01*
X81125Y958925D01*
X81458Y958800D01*
X81708Y958633D01*
X81917Y958383D01*
X82000Y958050D01*
G01X79500Y961150D02*
X82000D01*
X81500Y960650D01*
G01X79500D02*
Y961650D01*
G01X86292Y952767D02*
X86417Y952517D01*
X86500Y952225D01*
Y951892D01*
X86375Y951517D01*
X86167Y951225D01*
X85917Y951017D01*
X85500Y950850D01*
X85125Y950808D01*
X84750Y950892D01*
X84500Y951017D01*
X84250Y951267D01*
X84083Y951558D01*
X84000Y951850D01*
Y952142D01*
X84083Y952433D01*
X84208Y952683D01*
X84375Y952892D01*
G01Y954033D02*
X84167Y954283D01*
X84042Y954575D01*
X84000Y954950D01*
X84083Y955325D01*
X84250Y955617D01*
X84542Y955825D01*
X84875Y955867D01*
X85208Y955783D01*
X85417Y955575D01*
X85583Y955283D01*
X85625Y954992D01*
X85583Y954700D01*
X85417Y954325D01*
X86500Y954450D01*
Y955575D01*
G01X84292Y957342D02*
X84083Y957633D01*
X84000Y957967D01*
X84083Y958300D01*
X84333Y958592D01*
X84708Y958800D01*
X85083Y958883D01*
X85542D01*
X85917Y958800D01*
X86250Y958592D01*
X86417Y958342D01*
X86500Y958050D01*
X86417Y957717D01*
X86250Y957467D01*
X86000Y957300D01*
X85667Y957217D01*
X85375Y957300D01*
X85083Y957508D01*
X84917Y957758D01*
X84875Y958050D01*
X84958Y958383D01*
X85167Y958633D01*
X85542Y958883D01*
G01X84292Y960442D02*
X84083Y960733D01*
X84000Y961067D01*
X84083Y961400D01*
X84333Y961692D01*
X84708Y961900D01*
X85083Y961983D01*
X85542D01*
X85917Y961900D01*
X86250Y961692D01*
X86417Y961442D01*
X86500Y961150D01*
X86417Y960817D01*
X86250Y960567D01*
X86000Y960400D01*
X85667Y960317D01*
X85375Y960400D01*
X85083Y960608D01*
X84917Y960858D01*
X84875Y961150D01*
X84958Y961483D01*
X85167Y961733D01*
X85542Y961983D01*
G01X94292Y958267D02*
X94417Y958017D01*
X94500Y957725D01*
Y957392D01*
X94375Y957017D01*
X94167Y956725D01*
X93917Y956517D01*
X93500Y956350D01*
X93125Y956308D01*
X92750Y956392D01*
X92500Y956517D01*
X92250Y956767D01*
X92083Y957058D01*
X92000Y957350D01*
Y957642D01*
X92083Y957933D01*
X92208Y958183D01*
X92375Y958392D01*
G01X93042Y959658D02*
X93333Y959950D01*
X93500Y960200D01*
X93583Y960533D01*
X93500Y960825D01*
X93333Y961033D01*
X93083Y961200D01*
X92792Y961242D01*
X92542Y961200D01*
X92292Y961033D01*
X92083Y960783D01*
X92000Y960492D01*
X92083Y960158D01*
X92333Y959867D01*
X92708Y959700D01*
X93125Y959658D01*
X93667Y959742D01*
X93958Y959867D01*
X94250Y960075D01*
X94458Y960367D01*
X94500Y960658D01*
X94417Y960950D01*
X94208Y961158D01*
G01X94500Y963550D02*
X94417Y963217D01*
X94208Y962967D01*
X93958Y962800D01*
X93625Y962675D01*
X93250Y962633D01*
X92875Y962675D01*
X92542Y962800D01*
X92292Y962967D01*
X92083Y963217D01*
X92000Y963550D01*
X92083Y963883D01*
X92292Y964133D01*
X92542Y964300D01*
X92875Y964425D01*
X93250Y964467D01*
X93625Y964425D01*
X93958Y964300D01*
X94208Y964133D01*
X94417Y963883D01*
X94500Y963550D01*
G01Y966650D02*
X94417Y966317D01*
X94208Y966067D01*
X93958Y965900D01*
X93625Y965775D01*
X93250Y965733D01*
X92875Y965775D01*
X92542Y965900D01*
X92292Y966067D01*
X92083Y966317D01*
X92000Y966650D01*
X92083Y966983D01*
X92292Y967233D01*
X92542Y967400D01*
X92875Y967525D01*
X93250Y967567D01*
X93625Y967525D01*
X93958Y967400D01*
X94208Y967233D01*
X94417Y966983D01*
X94500Y966650D01*
G01X127033Y1004867D02*
Y1007367D01*
X125992D01*
X125658Y1007242D01*
X125450Y1007075D01*
X125367Y1006742D01*
X125450Y1006409D01*
X125700Y1006200D01*
X125992Y1006075D01*
X127033D01*
G01X125992D02*
X125367Y1004867D01*
G01X123100D02*
Y1007367D01*
X123600Y1006867D01*
G01Y1004867D02*
X122600D01*
G01X120792Y1006950D02*
X120542Y1007200D01*
X120250Y1007325D01*
X119917Y1007367D01*
X119500Y1007284D01*
X119208Y1007075D01*
X119125Y1006825D01*
X119167Y1006575D01*
X119333Y1006367D01*
X120167Y1005950D01*
X120542Y1005659D01*
X120792Y1005242D01*
X120875Y1004867D01*
X119125D01*
G01X116900D02*
Y1007367D01*
X117400Y1006867D01*
G01Y1004867D02*
X116400D01*
G01X113883D02*
X113800Y1005409D01*
X113675Y1005867D01*
X113508Y1006284D01*
X113300Y1006742D01*
X112967Y1007367D01*
X114633D01*
G01X107000Y994467D02*
X109500D01*
Y995508D01*
X109375Y995842D01*
X109208Y996050D01*
X108875Y996133D01*
X108542Y996050D01*
X108333Y995800D01*
X108208Y995508D01*
Y994467D01*
G01Y995508D02*
X107000Y996133D01*
G01Y998400D02*
X109500D01*
X109000Y997900D01*
G01X107000D02*
Y998900D01*
G01X109083Y1000708D02*
X109333Y1000958D01*
X109458Y1001250D01*
X109500Y1001583D01*
X109417Y1002000D01*
X109208Y1002292D01*
X108958Y1002375D01*
X108708Y1002333D01*
X108500Y1002167D01*
X108083Y1001333D01*
X107792Y1000958D01*
X107375Y1000708D01*
X107000Y1000625D01*
Y1002375D01*
G01X109083Y1003808D02*
X109333Y1004058D01*
X109458Y1004350D01*
X109500Y1004683D01*
X109417Y1005100D01*
X109208Y1005392D01*
X108958Y1005475D01*
X108708Y1005433D01*
X108500Y1005267D01*
X108083Y1004433D01*
X107792Y1004058D01*
X107375Y1003808D01*
X107000Y1003725D01*
Y1005475D01*
G01Y1007700D02*
X109500D01*
X109000Y1007200D01*
G01X107000D02*
Y1008200D01*
G01X121741Y993716D02*
X117741D01*
Y1001116D01*
G01X101950Y988200D02*
Y993200D01*
X106950D01*
G01X103500Y994517D02*
X106000D01*
Y995517D01*
X105875Y995850D01*
X105583Y996100D01*
X105250Y996183D01*
X104917Y996100D01*
X104667Y995892D01*
X104542Y995517D01*
Y994517D01*
G01X104750Y998700D02*
Y999533D01*
X104000D01*
X103750Y999283D01*
X103583Y998992D01*
X103500Y998575D01*
X103583Y998158D01*
X103750Y997867D01*
X104000Y997617D01*
X104292Y997450D01*
X104625Y997367D01*
X104917D01*
X105167Y997450D01*
X105458Y997617D01*
X105708Y997867D01*
X105875Y998117D01*
X106000Y998450D01*
Y998742D01*
X105917Y999075D01*
X105750Y999325D01*
G01X103500Y1001550D02*
X106000D01*
X105500Y1001050D01*
G01X103500D02*
Y1002050D01*
G01Y1004650D02*
X106000D01*
X105500Y1004150D01*
G01X103500D02*
Y1005150D01*
G01X95233Y998792D02*
X95483Y998917D01*
X95775Y999000D01*
X96108D01*
X96483Y998875D01*
X96775Y998667D01*
X96983Y998417D01*
X97150Y998000D01*
X97192Y997625D01*
X97108Y997250D01*
X96983Y997000D01*
X96733Y996750D01*
X96442Y996583D01*
X96150Y996500D01*
X95858D01*
X95567Y996583D01*
X95317Y996708D01*
X95108Y996875D01*
G01X93842Y997542D02*
X93550Y997833D01*
X93300Y998000D01*
X92967Y998083D01*
X92675Y998000D01*
X92467Y997833D01*
X92300Y997583D01*
X92258Y997292D01*
X92300Y997042D01*
X92467Y996792D01*
X92717Y996583D01*
X93008Y996500D01*
X93342Y996583D01*
X93633Y996833D01*
X93800Y997208D01*
X93842Y997625D01*
X93758Y998167D01*
X93633Y998458D01*
X93425Y998750D01*
X93133Y998958D01*
X92842Y999000D01*
X92550Y998917D01*
X92342Y998708D01*
G01X89950Y999000D02*
X90283Y998917D01*
X90533Y998708D01*
X90700Y998458D01*
X90825Y998125D01*
X90867Y997750D01*
X90825Y997375D01*
X90700Y997042D01*
X90533Y996792D01*
X90283Y996583D01*
X89950Y996500D01*
X89617Y996583D01*
X89367Y996792D01*
X89200Y997042D01*
X89075Y997375D01*
X89033Y997750D01*
X89075Y998125D01*
X89200Y998458D01*
X89367Y998708D01*
X89617Y998917D01*
X89950Y999000D01*
G01X86350Y996500D02*
Y999000D01*
X87892Y997208D01*
X85808D01*
G01X95326Y994487D02*
X95576Y994612D01*
X95868Y994695D01*
X96201D01*
X96576Y994570D01*
X96868Y994362D01*
X97076Y994112D01*
X97243Y993695D01*
X97285Y993320D01*
X97201Y992945D01*
X97076Y992695D01*
X96826Y992445D01*
X96535Y992278D01*
X96243Y992195D01*
X95951D01*
X95660Y992278D01*
X95410Y992403D01*
X95201Y992570D01*
G01X93935Y993237D02*
X93643Y993528D01*
X93393Y993695D01*
X93060Y993778D01*
X92768Y993695D01*
X92560Y993528D01*
X92393Y993278D01*
X92351Y992987D01*
X92393Y992737D01*
X92560Y992487D01*
X92810Y992278D01*
X93101Y992195D01*
X93435Y992278D01*
X93726Y992528D01*
X93893Y992903D01*
X93935Y993320D01*
X93851Y993862D01*
X93726Y994153D01*
X93518Y994445D01*
X93226Y994653D01*
X92935Y994695D01*
X92643Y994612D01*
X92435Y994403D01*
G01X90043Y994695D02*
X90376Y994612D01*
X90626Y994403D01*
X90793Y994153D01*
X90918Y993820D01*
X90960Y993445D01*
X90918Y993070D01*
X90793Y992737D01*
X90626Y992487D01*
X90376Y992278D01*
X90043Y992195D01*
X89710Y992278D01*
X89460Y992487D01*
X89293Y992737D01*
X89168Y993070D01*
X89126Y993445D01*
X89168Y993820D01*
X89293Y994153D01*
X89460Y994403D01*
X89710Y994612D01*
X90043Y994695D01*
G01X87735Y993237D02*
X87443Y993528D01*
X87193Y993695D01*
X86860Y993778D01*
X86568Y993695D01*
X86360Y993528D01*
X86193Y993278D01*
X86151Y992987D01*
X86193Y992737D01*
X86360Y992487D01*
X86610Y992278D01*
X86901Y992195D01*
X87235Y992278D01*
X87526Y992528D01*
X87693Y992903D01*
X87735Y993320D01*
X87651Y993862D01*
X87526Y994153D01*
X87318Y994445D01*
X87026Y994653D01*
X86735Y994695D01*
X86443Y994612D01*
X86235Y994403D01*
G01X125296Y1011017D02*
X125546Y1011142D01*
X125838Y1011225D01*
X126171D01*
X126546Y1011100D01*
X126838Y1010892D01*
X127046Y1010642D01*
X127213Y1010225D01*
X127255Y1009850D01*
X127171Y1009475D01*
X127046Y1009225D01*
X126796Y1008975D01*
X126505Y1008808D01*
X126213Y1008725D01*
X125921D01*
X125630Y1008808D01*
X125380Y1008933D01*
X125171Y1009100D01*
G01X123905Y1009767D02*
X123613Y1010058D01*
X123363Y1010225D01*
X123030Y1010308D01*
X122738Y1010225D01*
X122530Y1010058D01*
X122363Y1009808D01*
X122321Y1009517D01*
X122363Y1009267D01*
X122530Y1009017D01*
X122780Y1008808D01*
X123071Y1008725D01*
X123405Y1008808D01*
X123696Y1009058D01*
X123863Y1009433D01*
X123905Y1009850D01*
X123821Y1010392D01*
X123696Y1010683D01*
X123488Y1010975D01*
X123196Y1011183D01*
X122905Y1011225D01*
X122613Y1011142D01*
X122405Y1010933D01*
G01X120805Y1009767D02*
X120513Y1010058D01*
X120263Y1010225D01*
X119930Y1010308D01*
X119638Y1010225D01*
X119430Y1010058D01*
X119263Y1009808D01*
X119221Y1009517D01*
X119263Y1009267D01*
X119430Y1009017D01*
X119680Y1008808D01*
X119971Y1008725D01*
X120305Y1008808D01*
X120596Y1009058D01*
X120763Y1009433D01*
X120805Y1009850D01*
X120721Y1010392D01*
X120596Y1010683D01*
X120388Y1010975D01*
X120096Y1011183D01*
X119805Y1011225D01*
X119513Y1011142D01*
X119305Y1010933D01*
G01X117830Y1009100D02*
X117580Y1008892D01*
X117288Y1008767D01*
X116913Y1008725D01*
X116538Y1008808D01*
X116246Y1008975D01*
X116038Y1009267D01*
X115996Y1009600D01*
X116080Y1009933D01*
X116288Y1010142D01*
X116580Y1010308D01*
X116871Y1010350D01*
X117163Y1010308D01*
X117538Y1010142D01*
X117413Y1011225D01*
X116288D01*
G01X135883Y543000D02*
Y540500D01*
X134217D01*
G01X132867Y541000D02*
X132617Y540708D01*
X132283Y540542D01*
X131908Y540500D01*
X131575Y540542D01*
X131242Y540750D01*
X131033Y541000D01*
X130992Y541250D01*
X131075Y541542D01*
X131367Y541750D01*
X131658Y541833D01*
X132033D01*
G01X131658D02*
X131408Y541958D01*
X131200Y542167D01*
X131117Y542417D01*
X131200Y542667D01*
X131408Y542875D01*
X131783Y543000D01*
X132158Y542958D01*
X132533Y542792D01*
G01X140200Y544800D02*
X126800D01*
G01X140200Y552000D02*
Y544800D01*
G01X126800D02*
Y552000D01*
G01X143992Y541367D02*
X144117Y541117D01*
X144200Y540825D01*
Y540492D01*
X144075Y540117D01*
X143867Y539825D01*
X143617Y539617D01*
X143200Y539450D01*
X142825Y539408D01*
X142450Y539492D01*
X142200Y539617D01*
X141950Y539867D01*
X141783Y540158D01*
X141700Y540450D01*
Y540742D01*
X141783Y541033D01*
X141908Y541283D01*
X142075Y541492D01*
G01X142742Y542758D02*
X143033Y543050D01*
X143200Y543300D01*
X143283Y543633D01*
X143200Y543925D01*
X143033Y544133D01*
X142783Y544300D01*
X142492Y544342D01*
X142242Y544300D01*
X141992Y544133D01*
X141783Y543883D01*
X141700Y543592D01*
X141783Y543258D01*
X142033Y542967D01*
X142408Y542800D01*
X142825Y542758D01*
X143367Y542842D01*
X143658Y542967D01*
X143950Y543175D01*
X144158Y543467D01*
X144200Y543758D01*
X144117Y544050D01*
X143908Y544258D01*
G01X141700Y546650D02*
X144200D01*
X143700Y546150D01*
G01X141700D02*
Y547150D01*
G01X141992Y549042D02*
X141783Y549333D01*
X141700Y549667D01*
X141783Y550000D01*
X142033Y550292D01*
X142408Y550500D01*
X142783Y550583D01*
X143242D01*
X143617Y550500D01*
X143950Y550292D01*
X144117Y550042D01*
X144200Y549750D01*
X144117Y549417D01*
X143950Y549167D01*
X143700Y549000D01*
X143367Y548917D01*
X143075Y549000D01*
X142783Y549208D01*
X142617Y549458D01*
X142575Y549750D01*
X142658Y550083D01*
X142867Y550333D01*
X143242Y550583D01*
G01X148292Y541267D02*
X148417Y541017D01*
X148500Y540725D01*
Y540392D01*
X148375Y540017D01*
X148167Y539725D01*
X147917Y539517D01*
X147500Y539350D01*
X147125Y539308D01*
X146750Y539392D01*
X146500Y539517D01*
X146250Y539767D01*
X146083Y540058D01*
X146000Y540350D01*
Y540642D01*
X146083Y540933D01*
X146208Y541183D01*
X146375Y541392D01*
G01X147042Y542658D02*
X147333Y542950D01*
X147500Y543200D01*
X147583Y543533D01*
X147500Y543825D01*
X147333Y544033D01*
X147083Y544200D01*
X146792Y544242D01*
X146542Y544200D01*
X146292Y544033D01*
X146083Y543783D01*
X146000Y543492D01*
X146083Y543158D01*
X146333Y542867D01*
X146708Y542700D01*
X147125Y542658D01*
X147667Y542742D01*
X147958Y542867D01*
X148250Y543075D01*
X148458Y543367D01*
X148500Y543658D01*
X148417Y543950D01*
X148208Y544158D01*
G01X146000Y546550D02*
X148500D01*
X148000Y546050D01*
G01X146000D02*
Y547050D01*
G01Y549650D02*
X146042Y549942D01*
X146167Y550275D01*
X146375Y550483D01*
X146667Y550567D01*
X146958Y550483D01*
X147208Y550233D01*
X147333Y549858D01*
Y549442D01*
X147417Y549192D01*
X147625Y548983D01*
X147917Y548900D01*
X148208Y549025D01*
X148417Y549317D01*
X148500Y549650D01*
X148417Y549983D01*
X148208Y550275D01*
X147917Y550400D01*
X147625Y550317D01*
X147417Y550108D01*
X147333Y549858D01*
Y549442D01*
X147208Y549067D01*
X146958Y548817D01*
X146667Y548733D01*
X146375Y548817D01*
X146167Y549025D01*
X146042Y549358D01*
X146000Y549650D01*
G01X152292Y541267D02*
X152417Y541017D01*
X152500Y540725D01*
Y540392D01*
X152375Y540017D01*
X152167Y539725D01*
X151917Y539517D01*
X151500Y539350D01*
X151125Y539308D01*
X150750Y539392D01*
X150500Y539517D01*
X150250Y539767D01*
X150083Y540058D01*
X150000Y540350D01*
Y540642D01*
X150083Y540933D01*
X150208Y541183D01*
X150375Y541392D01*
G01X151042Y542658D02*
X151333Y542950D01*
X151500Y543200D01*
X151583Y543533D01*
X151500Y543825D01*
X151333Y544033D01*
X151083Y544200D01*
X150792Y544242D01*
X150542Y544200D01*
X150292Y544033D01*
X150083Y543783D01*
X150000Y543492D01*
X150083Y543158D01*
X150333Y542867D01*
X150708Y542700D01*
X151125Y542658D01*
X151667Y542742D01*
X151958Y542867D01*
X152250Y543075D01*
X152458Y543367D01*
X152500Y543658D01*
X152417Y543950D01*
X152208Y544158D01*
G01X150000Y546550D02*
X152500D01*
X152000Y546050D01*
G01X150000D02*
Y547050D01*
G01X151042Y548858D02*
X151333Y549150D01*
X151500Y549400D01*
X151583Y549733D01*
X151500Y550025D01*
X151333Y550233D01*
X151083Y550400D01*
X150792Y550442D01*
X150542Y550400D01*
X150292Y550233D01*
X150083Y549983D01*
X150000Y549692D01*
X150083Y549358D01*
X150333Y549067D01*
X150708Y548900D01*
X151125Y548858D01*
X151667Y548942D01*
X151958Y549067D01*
X152250Y549275D01*
X152458Y549567D01*
X152500Y549858D01*
X152417Y550150D01*
X152208Y550358D01*
G01X161292Y546267D02*
X161417Y546017D01*
X161500Y545725D01*
Y545392D01*
X161375Y545017D01*
X161167Y544725D01*
X160917Y544517D01*
X160500Y544350D01*
X160125Y544308D01*
X159750Y544392D01*
X159500Y544517D01*
X159250Y544767D01*
X159083Y545058D01*
X159000Y545350D01*
Y545642D01*
X159083Y545933D01*
X159208Y546183D01*
X159375Y546392D01*
G01X160042Y547658D02*
X160333Y547950D01*
X160500Y548200D01*
X160583Y548533D01*
X160500Y548825D01*
X160333Y549033D01*
X160083Y549200D01*
X159792Y549242D01*
X159542Y549200D01*
X159292Y549033D01*
X159083Y548783D01*
X159000Y548492D01*
X159083Y548158D01*
X159333Y547867D01*
X159708Y547700D01*
X160125Y547658D01*
X160667Y547742D01*
X160958Y547867D01*
X161250Y548075D01*
X161458Y548367D01*
X161500Y548658D01*
X161417Y548950D01*
X161208Y549158D01*
G01X159000Y551550D02*
X161500D01*
X161000Y551050D01*
G01X159000D02*
Y552050D01*
G01Y554567D02*
X159542Y554650D01*
X160000Y554775D01*
X160417Y554942D01*
X160875Y555150D01*
X161500Y555483D01*
Y553817D01*
G01X168650Y576200D02*
Y581200D01*
X173650D01*
G01Y553200D02*
X168650D01*
Y558200D01*
G01X169657Y573106D02*
X166657D01*
G01X169657Y563263D02*
X167657D01*
G01X166700Y582617D02*
X169200D01*
Y583617D01*
X169075Y583950D01*
X168783Y584200D01*
X168450Y584283D01*
X168117Y584200D01*
X167867Y583992D01*
X167742Y583617D01*
Y582617D01*
G01X167950Y586800D02*
Y587633D01*
X167200D01*
X166950Y587383D01*
X166783Y587092D01*
X166700Y586675D01*
X166783Y586258D01*
X166950Y585967D01*
X167200Y585717D01*
X167492Y585550D01*
X167825Y585467D01*
X168117D01*
X168367Y585550D01*
X168658Y585717D01*
X168908Y585967D01*
X169075Y586217D01*
X169200Y586550D01*
Y586842D01*
X169117Y587175D01*
X168950Y587425D01*
G01X166700Y589650D02*
X169200D01*
X168700Y589150D01*
G01X166700D02*
Y590150D01*
G01X167200Y591833D02*
X166908Y592083D01*
X166742Y592417D01*
X166700Y592792D01*
X166742Y593125D01*
X166950Y593458D01*
X167200Y593667D01*
X167450Y593708D01*
X167742Y593625D01*
X167950Y593333D01*
X168033Y593042D01*
Y592667D01*
G01Y593042D02*
X168158Y593292D01*
X168367Y593500D01*
X168617Y593583D01*
X168867Y593500D01*
X169075Y593292D01*
X169200Y592917D01*
X169158Y592542D01*
X168992Y592167D01*
G01X126800Y552000D02*
X140200D01*
G01X162233Y587292D02*
X162483Y587417D01*
X162775Y587500D01*
X163108D01*
X163483Y587375D01*
X163775Y587167D01*
X163983Y586917D01*
X164150Y586500D01*
X164192Y586125D01*
X164108Y585750D01*
X163983Y585500D01*
X163733Y585250D01*
X163442Y585083D01*
X163150Y585000D01*
X162858D01*
X162567Y585083D01*
X162317Y585208D01*
X162108Y585375D01*
G01X160842Y586042D02*
X160550Y586333D01*
X160300Y586500D01*
X159967Y586583D01*
X159675Y586500D01*
X159467Y586333D01*
X159300Y586083D01*
X159258Y585792D01*
X159300Y585542D01*
X159467Y585292D01*
X159717Y585083D01*
X160008Y585000D01*
X160342Y585083D01*
X160633Y585333D01*
X160800Y585708D01*
X160842Y586125D01*
X160758Y586667D01*
X160633Y586958D01*
X160425Y587250D01*
X160133Y587458D01*
X159842Y587500D01*
X159550Y587417D01*
X159342Y587208D01*
G01X157742Y587083D02*
X157492Y587333D01*
X157200Y587458D01*
X156867Y587500D01*
X156450Y587417D01*
X156158Y587208D01*
X156075Y586958D01*
X156117Y586708D01*
X156283Y586500D01*
X157117Y586083D01*
X157492Y585792D01*
X157742Y585375D01*
X157825Y585000D01*
X156075D01*
G01X153850D02*
Y587500D01*
X154350Y587000D01*
G01Y585000D02*
X153350D01*
G01X124000Y557967D02*
X126500D01*
Y559008D01*
X126375Y559342D01*
X126208Y559550D01*
X125875Y559633D01*
X125542Y559550D01*
X125333Y559300D01*
X125208Y559008D01*
Y557967D01*
G01Y559008D02*
X124000Y559633D01*
G01Y561900D02*
X126500D01*
X126000Y561400D01*
G01X124000D02*
Y562400D01*
G01X126083Y564208D02*
X126333Y564458D01*
X126458Y564750D01*
X126500Y565083D01*
X126417Y565500D01*
X126208Y565792D01*
X125958Y565875D01*
X125708Y565833D01*
X125500Y565667D01*
X125083Y564833D01*
X124792Y564458D01*
X124375Y564208D01*
X124000Y564125D01*
Y565875D01*
G01X126083Y567308D02*
X126333Y567558D01*
X126458Y567850D01*
X126500Y568183D01*
X126417Y568600D01*
X126208Y568892D01*
X125958Y568975D01*
X125708Y568933D01*
X125500Y568767D01*
X125083Y567933D01*
X124792Y567558D01*
X124375Y567308D01*
X124000Y567225D01*
Y568975D01*
G01X125042Y570408D02*
X125333Y570700D01*
X125500Y570950D01*
X125583Y571283D01*
X125500Y571575D01*
X125333Y571783D01*
X125083Y571950D01*
X124792Y571992D01*
X124542Y571950D01*
X124292Y571783D01*
X124083Y571533D01*
X124000Y571242D01*
X124083Y570908D01*
X124333Y570617D01*
X124708Y570450D01*
X125125Y570408D01*
X125667Y570492D01*
X125958Y570617D01*
X126250Y570825D01*
X126458Y571117D01*
X126500Y571408D01*
X126417Y571700D01*
X126208Y571908D01*
G01X162233Y582792D02*
X162483Y582917D01*
X162775Y583000D01*
X163108D01*
X163483Y582875D01*
X163775Y582667D01*
X163983Y582417D01*
X164150Y582000D01*
X164192Y581625D01*
X164108Y581250D01*
X163983Y581000D01*
X163733Y580750D01*
X163442Y580583D01*
X163150Y580500D01*
X162858D01*
X162567Y580583D01*
X162317Y580708D01*
X162108Y580875D01*
G01X160842Y581542D02*
X160550Y581833D01*
X160300Y582000D01*
X159967Y582083D01*
X159675Y582000D01*
X159467Y581833D01*
X159300Y581583D01*
X159258Y581292D01*
X159300Y581042D01*
X159467Y580792D01*
X159717Y580583D01*
X160008Y580500D01*
X160342Y580583D01*
X160633Y580833D01*
X160800Y581208D01*
X160842Y581625D01*
X160758Y582167D01*
X160633Y582458D01*
X160425Y582750D01*
X160133Y582958D01*
X159842Y583000D01*
X159550Y582917D01*
X159342Y582708D01*
G01X157742Y582583D02*
X157492Y582833D01*
X157200Y582958D01*
X156867Y583000D01*
X156450Y582917D01*
X156158Y582708D01*
X156075Y582458D01*
X156117Y582208D01*
X156283Y582000D01*
X157117Y581583D01*
X157492Y581292D01*
X157742Y580875D01*
X157825Y580500D01*
X156075D01*
G01X154767Y580875D02*
X154517Y580667D01*
X154225Y580542D01*
X153850Y580500D01*
X153475Y580583D01*
X153183Y580750D01*
X152975Y581042D01*
X152933Y581375D01*
X153017Y581708D01*
X153225Y581917D01*
X153517Y582083D01*
X153808Y582125D01*
X154100Y582083D01*
X154475Y581917D01*
X154350Y583000D01*
X153225D01*
G01X171101Y663943D02*
Y666443D01*
X169185Y663943D01*
Y666443D01*
G01X167960D02*
Y664651D01*
X167793Y664276D01*
X167460Y664026D01*
X167043Y663943D01*
X166626Y664026D01*
X166293Y664276D01*
X166126Y664651D01*
Y666443D01*
G01X163943D02*
Y663943D01*
G01X164901Y666443D02*
X162985D01*
G01X161760Y664443D02*
X161510Y664151D01*
X161176Y663985D01*
X160801Y663943D01*
X160468Y663985D01*
X160135Y664193D01*
X159926Y664443D01*
X159885Y664693D01*
X159968Y664985D01*
X160260Y665193D01*
X160551Y665276D01*
X160926D01*
G01X160551D02*
X160301Y665401D01*
X160093Y665610D01*
X160010Y665860D01*
X160093Y666110D01*
X160301Y666318D01*
X160676Y666443D01*
X161051Y666401D01*
X161426Y666235D01*
G01X129650Y970200D02*
Y965200D01*
X124650D01*
G01X128643Y971326D02*
X131643D01*
G01X128643Y981169D02*
X130643D01*
G01X156883Y944500D02*
Y942000D01*
X155217D01*
G01X153742Y944083D02*
X153492Y944333D01*
X153200Y944458D01*
X152867Y944500D01*
X152450Y944417D01*
X152158Y944208D01*
X152075Y943958D01*
X152117Y943708D01*
X152283Y943500D01*
X153117Y943083D01*
X153492Y942792D01*
X153742Y942375D01*
X153825Y942000D01*
X152075D01*
G01X130300Y988800D02*
Y947400D01*
X180900D01*
Y988800D01*
X130300D01*
G01X123600Y995700D02*
Y999700D01*
X131000D01*
G01X160536Y990641D02*
X163036D01*
Y991682D01*
X162911Y992016D01*
X162744Y992224D01*
X162411Y992307D01*
X162078Y992224D01*
X161869Y991974D01*
X161744Y991682D01*
Y990641D01*
G01Y991682D02*
X160536Y992307D01*
G01Y994574D02*
X163036D01*
X162536Y994074D01*
G01X160536D02*
Y995074D01*
G01X162619Y996882D02*
X162869Y997132D01*
X162994Y997424D01*
X163036Y997757D01*
X162953Y998174D01*
X162744Y998466D01*
X162494Y998549D01*
X162244Y998507D01*
X162036Y998341D01*
X161619Y997507D01*
X161328Y997132D01*
X160911Y996882D01*
X160536Y996799D01*
Y998549D01*
G01Y1000774D02*
X163036D01*
X162536Y1000274D01*
G01X160536D02*
Y1001274D01*
G01Y1003874D02*
X163036D01*
X162536Y1003374D01*
G01X160536D02*
Y1004374D01*
G01X153536Y991974D02*
X149536D01*
Y999374D01*
G01X144033Y1008500D02*
Y1011000D01*
X142992D01*
X142658Y1010875D01*
X142450Y1010708D01*
X142367Y1010375D01*
X142450Y1010042D01*
X142700Y1009833D01*
X142992Y1009708D01*
X144033D01*
G01X142992D02*
X142367Y1008500D01*
G01X140100D02*
Y1011000D01*
X140600Y1010500D01*
G01Y1008500D02*
X139600D01*
G01X137792Y1010583D02*
X137542Y1010833D01*
X137250Y1010958D01*
X136917Y1011000D01*
X136500Y1010917D01*
X136208Y1010708D01*
X136125Y1010458D01*
X136167Y1010208D01*
X136333Y1010000D01*
X137167Y1009583D01*
X137542Y1009292D01*
X137792Y1008875D01*
X137875Y1008500D01*
X136125D01*
G01X133900D02*
Y1011000D01*
X134400Y1010500D01*
G01Y1008500D02*
X133400D01*
G01X131592Y1009542D02*
X131300Y1009833D01*
X131050Y1010000D01*
X130717Y1010083D01*
X130425Y1010000D01*
X130217Y1009833D01*
X130050Y1009583D01*
X130008Y1009292D01*
X130050Y1009042D01*
X130217Y1008792D01*
X130467Y1008583D01*
X130758Y1008500D01*
X131092Y1008583D01*
X131383Y1008833D01*
X131550Y1009208D01*
X131592Y1009625D01*
X131508Y1010167D01*
X131383Y1010458D01*
X131175Y1010750D01*
X130883Y1010958D01*
X130592Y1011000D01*
X130300Y1010917D01*
X130092Y1010708D01*
G01X167292Y992267D02*
X167417Y992017D01*
X167500Y991725D01*
Y991392D01*
X167375Y991017D01*
X167167Y990725D01*
X166917Y990517D01*
X166500Y990350D01*
X166125Y990308D01*
X165750Y990392D01*
X165500Y990517D01*
X165250Y990767D01*
X165083Y991058D01*
X165000Y991350D01*
Y991642D01*
X165083Y991933D01*
X165208Y992183D01*
X165375Y992392D01*
G01X166042Y993658D02*
X166333Y993950D01*
X166500Y994200D01*
X166583Y994533D01*
X166500Y994825D01*
X166333Y995033D01*
X166083Y995200D01*
X165792Y995242D01*
X165542Y995200D01*
X165292Y995033D01*
X165083Y994783D01*
X165000Y994492D01*
X165083Y994158D01*
X165333Y993867D01*
X165708Y993700D01*
X166125Y993658D01*
X166667Y993742D01*
X166958Y993867D01*
X167250Y994075D01*
X167458Y994367D01*
X167500Y994658D01*
X167417Y994950D01*
X167208Y995158D01*
G01X167500Y997550D02*
X167417Y997217D01*
X167208Y996967D01*
X166958Y996800D01*
X166625Y996675D01*
X166250Y996633D01*
X165875Y996675D01*
X165542Y996800D01*
X165292Y996967D01*
X165083Y997217D01*
X165000Y997550D01*
X165083Y997883D01*
X165292Y998133D01*
X165542Y998300D01*
X165875Y998425D01*
X166250Y998467D01*
X166625Y998425D01*
X166958Y998300D01*
X167208Y998133D01*
X167417Y997883D01*
X167500Y997550D01*
G01X165000Y1000650D02*
X165042Y1000942D01*
X165167Y1001275D01*
X165375Y1001483D01*
X165667Y1001567D01*
X165958Y1001483D01*
X166208Y1001233D01*
X166333Y1000858D01*
Y1000442D01*
X166417Y1000192D01*
X166625Y999983D01*
X166917Y999900D01*
X167208Y1000025D01*
X167417Y1000317D01*
X167500Y1000650D01*
X167417Y1000983D01*
X167208Y1001275D01*
X166917Y1001400D01*
X166625Y1001317D01*
X166417Y1001108D01*
X166333Y1000858D01*
Y1000442D01*
X166208Y1000067D01*
X165958Y999817D01*
X165667Y999733D01*
X165375Y999817D01*
X165167Y1000025D01*
X165042Y1000358D01*
X165000Y1000650D01*
G01X168733Y1008792D02*
X168983Y1008917D01*
X169275Y1009000D01*
X169608D01*
X169983Y1008875D01*
X170275Y1008667D01*
X170483Y1008417D01*
X170650Y1008000D01*
X170692Y1007625D01*
X170608Y1007250D01*
X170483Y1007000D01*
X170233Y1006750D01*
X169942Y1006583D01*
X169650Y1006500D01*
X169358D01*
X169067Y1006583D01*
X168817Y1006708D01*
X168608Y1006875D01*
G01X167342Y1007542D02*
X167050Y1007833D01*
X166800Y1008000D01*
X166467Y1008083D01*
X166175Y1008000D01*
X165967Y1007833D01*
X165800Y1007583D01*
X165758Y1007292D01*
X165800Y1007042D01*
X165967Y1006792D01*
X166217Y1006583D01*
X166508Y1006500D01*
X166842Y1006583D01*
X167133Y1006833D01*
X167300Y1007208D01*
X167342Y1007625D01*
X167258Y1008167D01*
X167133Y1008458D01*
X166925Y1008750D01*
X166633Y1008958D01*
X166342Y1009000D01*
X166050Y1008917D01*
X165842Y1008708D01*
G01X163450Y1009000D02*
X163783Y1008917D01*
X164033Y1008708D01*
X164200Y1008458D01*
X164325Y1008125D01*
X164367Y1007750D01*
X164325Y1007375D01*
X164200Y1007042D01*
X164033Y1006792D01*
X163783Y1006583D01*
X163450Y1006500D01*
X163117Y1006583D01*
X162867Y1006792D01*
X162700Y1007042D01*
X162575Y1007375D01*
X162533Y1007750D01*
X162575Y1008125D01*
X162700Y1008458D01*
X162867Y1008708D01*
X163117Y1008917D01*
X163450Y1009000D01*
G01X161058Y1006792D02*
X160767Y1006583D01*
X160433Y1006500D01*
X160100Y1006583D01*
X159808Y1006833D01*
X159600Y1007208D01*
X159517Y1007583D01*
Y1008042D01*
X159600Y1008417D01*
X159808Y1008750D01*
X160058Y1008917D01*
X160350Y1009000D01*
X160683Y1008917D01*
X160933Y1008750D01*
X161100Y1008500D01*
X161183Y1008167D01*
X161100Y1007875D01*
X160892Y1007583D01*
X160642Y1007417D01*
X160350Y1007375D01*
X160017Y1007458D01*
X159767Y1007667D01*
X159517Y1008042D01*
G01X185517Y548000D02*
Y546208D01*
X185350Y545833D01*
X185017Y545583D01*
X184600Y545500D01*
X184183Y545583D01*
X183850Y545833D01*
X183683Y546208D01*
Y548000D01*
G01X182292Y547583D02*
X182042Y547833D01*
X181750Y547958D01*
X181417Y548000D01*
X181000Y547917D01*
X180708Y547708D01*
X180625Y547458D01*
X180667Y547208D01*
X180833Y547000D01*
X181667Y546583D01*
X182042Y546292D01*
X182292Y545875D01*
X182375Y545500D01*
X180625D01*
G01X178400D02*
Y548000D01*
X178900Y547500D01*
G01Y545500D02*
X177900D01*
G01X197000Y576800D02*
Y535400D01*
X247600D01*
Y576800D01*
X197000D01*
G01X190033Y593766D02*
Y596266D01*
X188992D01*
X188658Y596141D01*
X188450Y595974D01*
X188367Y595641D01*
X188450Y595308D01*
X188700Y595099D01*
X188992Y594974D01*
X190033D01*
G01X188992D02*
X188367Y593766D01*
G01X186100D02*
Y596266D01*
X186600Y595766D01*
G01Y593766D02*
X185600D01*
G01X183792Y595849D02*
X183542Y596099D01*
X183250Y596224D01*
X182917Y596266D01*
X182500Y596183D01*
X182208Y595974D01*
X182125Y595724D01*
X182167Y595474D01*
X182333Y595266D01*
X183167Y594849D01*
X183542Y594558D01*
X183792Y594141D01*
X183875Y593766D01*
X182125D01*
G01X180817Y594266D02*
X180567Y593974D01*
X180233Y593808D01*
X179858Y593766D01*
X179525Y593808D01*
X179192Y594016D01*
X178983Y594266D01*
X178942Y594516D01*
X179025Y594808D01*
X179317Y595016D01*
X179608Y595099D01*
X179983D01*
G01X179608D02*
X179358Y595224D01*
X179150Y595433D01*
X179067Y595683D01*
X179150Y595933D01*
X179358Y596141D01*
X179733Y596266D01*
X180108Y596224D01*
X180483Y596058D01*
G01X177592Y594808D02*
X177300Y595099D01*
X177050Y595266D01*
X176717Y595349D01*
X176425Y595266D01*
X176217Y595099D01*
X176050Y594849D01*
X176008Y594558D01*
X176050Y594308D01*
X176217Y594058D01*
X176467Y593849D01*
X176758Y593766D01*
X177092Y593849D01*
X177383Y594099D01*
X177550Y594474D01*
X177592Y594891D01*
X177508Y595433D01*
X177383Y595724D01*
X177175Y596016D01*
X176883Y596224D01*
X176592Y596266D01*
X176300Y596183D01*
X176092Y595974D01*
G01X190100Y583700D02*
Y587700D01*
X197500D01*
G01X220236Y579974D02*
X216236D01*
Y587374D01*
G01X170700Y582567D02*
X173200D01*
Y583608D01*
X173075Y583942D01*
X172908Y584150D01*
X172575Y584233D01*
X172242Y584150D01*
X172033Y583900D01*
X171908Y583608D01*
Y582567D01*
G01Y583608D02*
X170700Y584233D01*
G01Y586500D02*
X173200D01*
X172700Y586000D01*
G01X170700D02*
Y587000D01*
G01X172783Y588808D02*
X173033Y589058D01*
X173158Y589350D01*
X173200Y589683D01*
X173117Y590100D01*
X172908Y590392D01*
X172658Y590475D01*
X172408Y590433D01*
X172200Y590267D01*
X171783Y589433D01*
X171492Y589058D01*
X171075Y588808D01*
X170700Y588725D01*
Y590475D01*
G01Y593200D02*
X173200D01*
X171408Y591658D01*
Y593742D01*
G01X170700Y595800D02*
X173200D01*
X172700Y595300D01*
G01X170700D02*
Y596300D01*
G01X188441Y581716D02*
X184441D01*
Y589116D01*
G01X196350Y558200D02*
Y553200D01*
X191350D01*
G01X195343Y559326D02*
X198343D01*
G01X195343Y569169D02*
X197343D01*
G01X207033Y593500D02*
Y596000D01*
X205992D01*
X205658Y595875D01*
X205450Y595708D01*
X205367Y595375D01*
X205450Y595042D01*
X205700Y594833D01*
X205992Y594708D01*
X207033D01*
G01X205992D02*
X205367Y593500D01*
G01X203100D02*
Y596000D01*
X203600Y595500D01*
G01Y593500D02*
X202600D01*
G01X200792Y595583D02*
X200542Y595833D01*
X200250Y595958D01*
X199917Y596000D01*
X199500Y595917D01*
X199208Y595708D01*
X199125Y595458D01*
X199167Y595208D01*
X199333Y595000D01*
X200167Y594583D01*
X200542Y594292D01*
X200792Y593875D01*
X200875Y593500D01*
X199125D01*
G01X197817Y594000D02*
X197567Y593708D01*
X197233Y593542D01*
X196858Y593500D01*
X196525Y593542D01*
X196192Y593750D01*
X195983Y594000D01*
X195942Y594250D01*
X196025Y594542D01*
X196317Y594750D01*
X196608Y594833D01*
X196983D01*
G01X196608D02*
X196358Y594958D01*
X196150Y595167D01*
X196067Y595417D01*
X196150Y595667D01*
X196358Y595875D01*
X196733Y596000D01*
X197108Y595958D01*
X197483Y595792D01*
G01X194717Y593875D02*
X194467Y593667D01*
X194175Y593542D01*
X193800Y593500D01*
X193425Y593583D01*
X193133Y593750D01*
X192925Y594042D01*
X192883Y594375D01*
X192967Y594708D01*
X193175Y594917D01*
X193467Y595083D01*
X193758Y595125D01*
X194050Y595083D01*
X194425Y594917D01*
X194300Y596000D01*
X193175D01*
G01X188733Y600292D02*
X188983Y600417D01*
X189275Y600500D01*
X189608D01*
X189983Y600375D01*
X190275Y600167D01*
X190483Y599917D01*
X190650Y599500D01*
X190692Y599125D01*
X190608Y598750D01*
X190483Y598500D01*
X190233Y598250D01*
X189942Y598083D01*
X189650Y598000D01*
X189358D01*
X189067Y598083D01*
X188817Y598208D01*
X188608Y598375D01*
G01X187342Y599042D02*
X187050Y599333D01*
X186800Y599500D01*
X186467Y599583D01*
X186175Y599500D01*
X185967Y599333D01*
X185800Y599083D01*
X185758Y598792D01*
X185800Y598542D01*
X185967Y598292D01*
X186217Y598083D01*
X186508Y598000D01*
X186842Y598083D01*
X187133Y598333D01*
X187300Y598708D01*
X187342Y599125D01*
X187258Y599667D01*
X187133Y599958D01*
X186925Y600250D01*
X186633Y600458D01*
X186342Y600500D01*
X186050Y600417D01*
X185842Y600208D01*
G01X184242Y599042D02*
X183950Y599333D01*
X183700Y599500D01*
X183367Y599583D01*
X183075Y599500D01*
X182867Y599333D01*
X182700Y599083D01*
X182658Y598792D01*
X182700Y598542D01*
X182867Y598292D01*
X183117Y598083D01*
X183408Y598000D01*
X183742Y598083D01*
X184033Y598333D01*
X184200Y598708D01*
X184242Y599125D01*
X184158Y599667D01*
X184033Y599958D01*
X183825Y600250D01*
X183533Y600458D01*
X183242Y600500D01*
X182950Y600417D01*
X182742Y600208D01*
G01X181142Y599042D02*
X180850Y599333D01*
X180600Y599500D01*
X180267Y599583D01*
X179975Y599500D01*
X179767Y599333D01*
X179600Y599083D01*
X179558Y598792D01*
X179600Y598542D01*
X179767Y598292D01*
X180017Y598083D01*
X180308Y598000D01*
X180642Y598083D01*
X180933Y598333D01*
X181100Y598708D01*
X181142Y599125D01*
X181058Y599667D01*
X180933Y599958D01*
X180725Y600250D01*
X180433Y600458D01*
X180142Y600500D01*
X179850Y600417D01*
X179642Y600208D01*
G01X195100Y939000D02*
Y936500D01*
G01X196058Y939000D02*
X194142D01*
G01X191083Y938792D02*
X191333Y938917D01*
X191625Y939000D01*
X191958D01*
X192333Y938875D01*
X192625Y938667D01*
X192833Y938417D01*
X193000Y938000D01*
X193042Y937625D01*
X192958Y937250D01*
X192833Y937000D01*
X192583Y936750D01*
X192292Y936583D01*
X192000Y936500D01*
X191708D01*
X191417Y936583D01*
X191167Y936708D01*
X190958Y936875D01*
G01X189817D02*
X189567Y936667D01*
X189275Y936542D01*
X188900Y936500D01*
X188525Y936583D01*
X188233Y936750D01*
X188025Y937042D01*
X187983Y937375D01*
X188067Y937708D01*
X188275Y937917D01*
X188567Y938083D01*
X188858Y938125D01*
X189150Y938083D01*
X189525Y937917D01*
X189400Y939000D01*
X188275D01*
G01X182400Y980600D02*
Y991800D01*
G01X200400Y980600D02*
X182400D01*
G01X200400Y991800D02*
Y980600D01*
G01Y979900D02*
Y968700D01*
G01X182400Y979900D02*
X200400D01*
G01X182400Y968700D02*
Y979900D01*
G01X200400Y941500D02*
Y952700D01*
G01X182400Y941500D02*
X200400D01*
G01X182400Y952700D02*
Y941500D01*
G01X194600Y1026000D02*
Y1023500D01*
G01X195558Y1026000D02*
X193642D01*
G01X190583Y1025792D02*
X190833Y1025917D01*
X191125Y1026000D01*
X191458D01*
X191833Y1025875D01*
X192125Y1025667D01*
X192333Y1025417D01*
X192500Y1025000D01*
X192542Y1024625D01*
X192458Y1024250D01*
X192333Y1024000D01*
X192083Y1023750D01*
X191792Y1023583D01*
X191500Y1023500D01*
X191208D01*
X190917Y1023583D01*
X190667Y1023708D01*
X190458Y1023875D01*
G01X189108Y1023792D02*
X188817Y1023583D01*
X188483Y1023500D01*
X188150Y1023583D01*
X187858Y1023833D01*
X187650Y1024208D01*
X187567Y1024583D01*
Y1025042D01*
X187650Y1025417D01*
X187858Y1025750D01*
X188108Y1025917D01*
X188400Y1026000D01*
X188733Y1025917D01*
X188983Y1025750D01*
X189150Y1025500D01*
X189233Y1025167D01*
X189150Y1024875D01*
X188942Y1024583D01*
X188692Y1024417D01*
X188400Y1024375D01*
X188067Y1024458D01*
X187817Y1024667D01*
X187567Y1025042D01*
G01X182400Y1019000D02*
Y1007800D01*
G01X200400Y1019000D02*
X182400D01*
G01X200400Y1007800D02*
Y1019000D01*
G01X209692Y1006167D02*
X209817Y1005917D01*
X209900Y1005625D01*
Y1005292D01*
X209775Y1004917D01*
X209567Y1004625D01*
X209317Y1004417D01*
X208900Y1004250D01*
X208525Y1004208D01*
X208150Y1004292D01*
X207900Y1004417D01*
X207650Y1004667D01*
X207483Y1004958D01*
X207400Y1005250D01*
Y1005542D01*
X207483Y1005833D01*
X207608Y1006083D01*
X207775Y1006292D01*
G01X208442Y1007558D02*
X208733Y1007850D01*
X208900Y1008100D01*
X208983Y1008433D01*
X208900Y1008725D01*
X208733Y1008933D01*
X208483Y1009100D01*
X208192Y1009142D01*
X207942Y1009100D01*
X207692Y1008933D01*
X207483Y1008683D01*
X207400Y1008392D01*
X207483Y1008058D01*
X207733Y1007767D01*
X208108Y1007600D01*
X208525Y1007558D01*
X209067Y1007642D01*
X209358Y1007767D01*
X209650Y1007975D01*
X209858Y1008267D01*
X209900Y1008558D01*
X209817Y1008850D01*
X209608Y1009058D01*
G01X207400Y1011450D02*
X209900D01*
X209400Y1010950D01*
G01X207400D02*
Y1011950D01*
G01X207900Y1013633D02*
X207608Y1013883D01*
X207442Y1014217D01*
X207400Y1014592D01*
X207442Y1014925D01*
X207650Y1015258D01*
X207900Y1015467D01*
X208150Y1015508D01*
X208442Y1015425D01*
X208650Y1015133D01*
X208733Y1014842D01*
Y1014467D01*
G01Y1014842D02*
X208858Y1015092D01*
X209067Y1015300D01*
X209317Y1015383D01*
X209567Y1015300D01*
X209775Y1015092D01*
X209900Y1014717D01*
X209858Y1014342D01*
X209692Y1013967D01*
G01X217492Y1006167D02*
X217617Y1005917D01*
X217700Y1005625D01*
Y1005292D01*
X217575Y1004917D01*
X217367Y1004625D01*
X217117Y1004417D01*
X216700Y1004250D01*
X216325Y1004208D01*
X215950Y1004292D01*
X215700Y1004417D01*
X215450Y1004667D01*
X215283Y1004958D01*
X215200Y1005250D01*
Y1005542D01*
X215283Y1005833D01*
X215408Y1006083D01*
X215575Y1006292D01*
G01X216242Y1007558D02*
X216533Y1007850D01*
X216700Y1008100D01*
X216783Y1008433D01*
X216700Y1008725D01*
X216533Y1008933D01*
X216283Y1009100D01*
X215992Y1009142D01*
X215742Y1009100D01*
X215492Y1008933D01*
X215283Y1008683D01*
X215200Y1008392D01*
X215283Y1008058D01*
X215533Y1007767D01*
X215908Y1007600D01*
X216325Y1007558D01*
X216867Y1007642D01*
X217158Y1007767D01*
X217450Y1007975D01*
X217658Y1008267D01*
X217700Y1008558D01*
X217617Y1008850D01*
X217408Y1009058D01*
G01X215200Y1011450D02*
X217700D01*
X217200Y1010950D01*
G01X215200D02*
Y1011950D01*
G01X217283Y1013758D02*
X217533Y1014008D01*
X217658Y1014300D01*
X217700Y1014633D01*
X217617Y1015050D01*
X217408Y1015342D01*
X217158Y1015425D01*
X216908Y1015383D01*
X216700Y1015217D01*
X216283Y1014383D01*
X215992Y1014008D01*
X215575Y1013758D01*
X215200Y1013675D01*
Y1015425D01*
G01X263650Y527000D02*
Y524500D01*
G01X264608Y527000D02*
X262692D01*
G01X259633Y526792D02*
X259883Y526917D01*
X260175Y527000D01*
X260508D01*
X260883Y526875D01*
X261175Y526667D01*
X261383Y526417D01*
X261550Y526000D01*
X261592Y525625D01*
X261508Y525250D01*
X261383Y525000D01*
X261133Y524750D01*
X260842Y524583D01*
X260550Y524500D01*
X260258D01*
X259967Y524583D01*
X259717Y524708D01*
X259508Y524875D01*
G01X257450Y524500D02*
Y527000D01*
X257950Y526500D01*
G01Y524500D02*
X256950D01*
G01X254350Y527000D02*
X254683Y526917D01*
X254933Y526708D01*
X255100Y526458D01*
X255225Y526125D01*
X255267Y525750D01*
X255225Y525375D01*
X255100Y525042D01*
X254933Y524792D01*
X254683Y524583D01*
X254350Y524500D01*
X254017Y524583D01*
X253767Y524792D01*
X253600Y525042D01*
X253475Y525375D01*
X253433Y525750D01*
X253475Y526125D01*
X253600Y526458D01*
X253767Y526708D01*
X254017Y526917D01*
X254350Y527000D01*
G01X249100Y529500D02*
X267100D01*
G01X249100Y540700D02*
Y529500D01*
G01X224883Y533000D02*
Y530500D01*
X223217D01*
G01X220450D02*
Y533000D01*
X221992Y531208D01*
X219908D01*
G01X226736Y578641D02*
X229236D01*
Y579682D01*
X229111Y580016D01*
X228944Y580224D01*
X228611Y580307D01*
X228278Y580224D01*
X228069Y579974D01*
X227944Y579682D01*
Y578641D01*
G01Y579682D02*
X226736Y580307D01*
G01Y582574D02*
X229236D01*
X228736Y582074D01*
G01X226736D02*
Y583074D01*
G01X228819Y584882D02*
X229069Y585132D01*
X229194Y585424D01*
X229236Y585757D01*
X229153Y586174D01*
X228944Y586466D01*
X228694Y586549D01*
X228444Y586507D01*
X228236Y586341D01*
X227819Y585507D01*
X227528Y585132D01*
X227111Y584882D01*
X226736Y584799D01*
Y586549D01*
G01X227236Y587857D02*
X226944Y588107D01*
X226778Y588441D01*
X226736Y588816D01*
X226778Y589149D01*
X226986Y589482D01*
X227236Y589691D01*
X227486Y589732D01*
X227778Y589649D01*
X227986Y589357D01*
X228069Y589066D01*
Y588691D01*
G01Y589066D02*
X228194Y589316D01*
X228403Y589524D01*
X228653Y589607D01*
X228903Y589524D01*
X229111Y589316D01*
X229236Y588941D01*
X229194Y588566D01*
X229028Y588191D01*
G01X229236Y591874D02*
X229153Y591541D01*
X228944Y591291D01*
X228694Y591124D01*
X228361Y590999D01*
X227986Y590957D01*
X227611Y590999D01*
X227278Y591124D01*
X227028Y591291D01*
X226819Y591541D01*
X226736Y591874D01*
X226819Y592207D01*
X227028Y592457D01*
X227278Y592624D01*
X227611Y592749D01*
X227986Y592791D01*
X228361Y592749D01*
X228694Y592624D01*
X228944Y592457D01*
X229153Y592207D01*
X229236Y591874D01*
G01X249100Y568600D02*
Y579800D01*
G01X267100Y568600D02*
X249100D01*
G01Y607000D02*
Y595800D01*
G01Y567900D02*
X267100D01*
G01X249100Y556700D02*
Y567900D01*
G01X233292Y580267D02*
X233417Y580017D01*
X233500Y579725D01*
Y579392D01*
X233375Y579017D01*
X233167Y578725D01*
X232917Y578517D01*
X232500Y578350D01*
X232125Y578308D01*
X231750Y578392D01*
X231500Y578517D01*
X231250Y578767D01*
X231083Y579058D01*
X231000Y579350D01*
Y579642D01*
X231083Y579933D01*
X231208Y580183D01*
X231375Y580392D01*
G01X232042Y581658D02*
X232333Y581950D01*
X232500Y582200D01*
X232583Y582533D01*
X232500Y582825D01*
X232333Y583033D01*
X232083Y583200D01*
X231792Y583242D01*
X231542Y583200D01*
X231292Y583033D01*
X231083Y582783D01*
X231000Y582492D01*
X231083Y582158D01*
X231333Y581867D01*
X231708Y581700D01*
X232125Y581658D01*
X232667Y581742D01*
X232958Y581867D01*
X233250Y582075D01*
X233458Y582367D01*
X233500Y582658D01*
X233417Y582950D01*
X233208Y583158D01*
G01X233083Y584758D02*
X233333Y585008D01*
X233458Y585300D01*
X233500Y585633D01*
X233417Y586050D01*
X233208Y586342D01*
X232958Y586425D01*
X232708Y586383D01*
X232500Y586217D01*
X232083Y585383D01*
X231792Y585008D01*
X231375Y584758D01*
X231000Y584675D01*
Y586425D01*
G01Y589150D02*
X233500D01*
X231708Y587608D01*
Y589692D01*
G01X234733Y597292D02*
X234983Y597417D01*
X235275Y597500D01*
X235608D01*
X235983Y597375D01*
X236275Y597167D01*
X236483Y596917D01*
X236650Y596500D01*
X236692Y596125D01*
X236608Y595750D01*
X236483Y595500D01*
X236233Y595250D01*
X235942Y595083D01*
X235650Y595000D01*
X235358D01*
X235067Y595083D01*
X234817Y595208D01*
X234608Y595375D01*
G01X233342Y596042D02*
X233050Y596333D01*
X232800Y596500D01*
X232467Y596583D01*
X232175Y596500D01*
X231967Y596333D01*
X231800Y596083D01*
X231758Y595792D01*
X231800Y595542D01*
X231967Y595292D01*
X232217Y595083D01*
X232508Y595000D01*
X232842Y595083D01*
X233133Y595333D01*
X233300Y595708D01*
X233342Y596125D01*
X233258Y596667D01*
X233133Y596958D01*
X232925Y597250D01*
X232633Y597458D01*
X232342Y597500D01*
X232050Y597417D01*
X231842Y597208D01*
G01X230242Y597083D02*
X229992Y597333D01*
X229700Y597458D01*
X229367Y597500D01*
X228950Y597417D01*
X228658Y597208D01*
X228575Y596958D01*
X228617Y596708D01*
X228783Y596500D01*
X229617Y596083D01*
X229992Y595792D01*
X230242Y595375D01*
X230325Y595000D01*
X228575D01*
G01X227142Y596042D02*
X226850Y596333D01*
X226600Y596500D01*
X226267Y596583D01*
X225975Y596500D01*
X225767Y596333D01*
X225600Y596083D01*
X225558Y595792D01*
X225600Y595542D01*
X225767Y595292D01*
X226017Y595083D01*
X226308Y595000D01*
X226642Y595083D01*
X226933Y595333D01*
X227100Y595708D01*
X227142Y596125D01*
X227058Y596667D01*
X226933Y596958D01*
X226725Y597250D01*
X226433Y597458D01*
X226142Y597500D01*
X225850Y597417D01*
X225642Y597208D01*
G01X261700Y613800D02*
Y611300D01*
G01X262658Y613800D02*
X260742D01*
G01X257683Y613592D02*
X257933Y613717D01*
X258225Y613800D01*
X258558D01*
X258933Y613675D01*
X259225Y613467D01*
X259433Y613217D01*
X259600Y612800D01*
X259642Y612425D01*
X259558Y612050D01*
X259433Y611800D01*
X259183Y611550D01*
X258892Y611383D01*
X258600Y611300D01*
X258308D01*
X258017Y611383D01*
X257767Y611508D01*
X257558Y611675D01*
G01X256292Y612342D02*
X256000Y612633D01*
X255750Y612800D01*
X255417Y612883D01*
X255125Y612800D01*
X254917Y612633D01*
X254750Y612383D01*
X254708Y612092D01*
X254750Y611842D01*
X254917Y611592D01*
X255167Y611383D01*
X255458Y611300D01*
X255792Y611383D01*
X256083Y611633D01*
X256250Y612008D01*
X256292Y612425D01*
X256208Y612967D01*
X256083Y613258D01*
X255875Y613550D01*
X255583Y613758D01*
X255292Y613800D01*
X255000Y613717D01*
X254792Y613508D01*
G01X267100Y607000D02*
X249100D01*
G01X241483Y991000D02*
Y993500D01*
X240483D01*
X240150Y993375D01*
X239900Y993083D01*
X239817Y992750D01*
X239900Y992417D01*
X240108Y992167D01*
X240483Y992042D01*
X241483D01*
G01X237300Y992250D02*
X236467D01*
Y991500D01*
X236717Y991250D01*
X237008Y991083D01*
X237425Y991000D01*
X237842Y991083D01*
X238133Y991250D01*
X238383Y991500D01*
X238550Y991792D01*
X238633Y992125D01*
Y992417D01*
X238550Y992667D01*
X238383Y992958D01*
X238133Y993208D01*
X237883Y993375D01*
X237550Y993500D01*
X237258D01*
X236925Y993417D01*
X236675Y993250D01*
G01X234450Y991000D02*
Y993500D01*
X234950Y993000D01*
G01Y991000D02*
X233950D01*
G01X231350Y993500D02*
X231683Y993417D01*
X231933Y993208D01*
X232100Y992958D01*
X232225Y992625D01*
X232267Y992250D01*
X232225Y991875D01*
X232100Y991542D01*
X231933Y991292D01*
X231683Y991083D01*
X231350Y991000D01*
X231017Y991083D01*
X230767Y991292D01*
X230600Y991542D01*
X230475Y991875D01*
X230433Y992250D01*
X230475Y992625D01*
X230600Y992958D01*
X230767Y993208D01*
X231017Y993417D01*
X231350Y993500D01*
G01X225292Y1006167D02*
X225417Y1005917D01*
X225500Y1005625D01*
Y1005292D01*
X225375Y1004917D01*
X225167Y1004625D01*
X224917Y1004417D01*
X224500Y1004250D01*
X224125Y1004208D01*
X223750Y1004292D01*
X223500Y1004417D01*
X223250Y1004667D01*
X223083Y1004958D01*
X223000Y1005250D01*
Y1005542D01*
X223083Y1005833D01*
X223208Y1006083D01*
X223375Y1006292D01*
G01X224042Y1007558D02*
X224333Y1007850D01*
X224500Y1008100D01*
X224583Y1008433D01*
X224500Y1008725D01*
X224333Y1008933D01*
X224083Y1009100D01*
X223792Y1009142D01*
X223542Y1009100D01*
X223292Y1008933D01*
X223083Y1008683D01*
X223000Y1008392D01*
X223083Y1008058D01*
X223333Y1007767D01*
X223708Y1007600D01*
X224125Y1007558D01*
X224667Y1007642D01*
X224958Y1007767D01*
X225250Y1007975D01*
X225458Y1008267D01*
X225500Y1008558D01*
X225417Y1008850D01*
X225208Y1009058D01*
G01X223000Y1011450D02*
X225500D01*
X225000Y1010950D01*
G01X223000D02*
Y1011950D01*
G01Y1014550D02*
X225500D01*
X225000Y1014050D01*
G01X223000D02*
Y1015050D01*
G01X267100Y529500D02*
Y540700D01*
G01Y579800D02*
Y568600D01*
G01Y595800D02*
Y607000D01*
G01Y567900D02*
Y556700D01*
G01X307983Y579500D02*
Y582000D01*
X306983D01*
X306650Y581875D01*
X306400Y581583D01*
X306317Y581250D01*
X306400Y580917D01*
X306608Y580667D01*
X306983Y580542D01*
X307983D01*
G01X303800Y580750D02*
X302967D01*
Y580000D01*
X303217Y579750D01*
X303508Y579583D01*
X303925Y579500D01*
X304342Y579583D01*
X304633Y579750D01*
X304883Y580000D01*
X305050Y580292D01*
X305133Y580625D01*
Y580917D01*
X305050Y581167D01*
X304883Y581458D01*
X304633Y581708D01*
X304383Y581875D01*
X304050Y582000D01*
X303758D01*
X303425Y581917D01*
X303175Y581750D01*
G01X300950Y579500D02*
Y582000D01*
X301450Y581500D01*
G01Y579500D02*
X300450D01*
G01X298642Y581583D02*
X298392Y581833D01*
X298100Y581958D01*
X297767Y582000D01*
X297350Y581917D01*
X297058Y581708D01*
X296975Y581458D01*
X297017Y581208D01*
X297183Y581000D01*
X298017Y580583D01*
X298392Y580292D01*
X298642Y579875D01*
X298725Y579500D01*
X296975D01*
G01X276392Y593167D02*
X276517Y592917D01*
X276600Y592625D01*
Y592292D01*
X276475Y591917D01*
X276267Y591625D01*
X276017Y591417D01*
X275600Y591250D01*
X275225Y591208D01*
X274850Y591292D01*
X274600Y591417D01*
X274350Y591667D01*
X274183Y591958D01*
X274100Y592250D01*
Y592542D01*
X274183Y592833D01*
X274308Y593083D01*
X274475Y593292D01*
G01X275142Y594558D02*
X275433Y594850D01*
X275600Y595100D01*
X275683Y595433D01*
X275600Y595725D01*
X275433Y595933D01*
X275183Y596100D01*
X274892Y596142D01*
X274642Y596100D01*
X274392Y595933D01*
X274183Y595683D01*
X274100Y595392D01*
X274183Y595058D01*
X274433Y594767D01*
X274808Y594600D01*
X275225Y594558D01*
X275767Y594642D01*
X276058Y594767D01*
X276350Y594975D01*
X276558Y595267D01*
X276600Y595558D01*
X276517Y595850D01*
X276308Y596058D01*
G01X274600Y597533D02*
X274308Y597783D01*
X274142Y598117D01*
X274100Y598492D01*
X274142Y598825D01*
X274350Y599158D01*
X274600Y599367D01*
X274850Y599408D01*
X275142Y599325D01*
X275350Y599033D01*
X275433Y598742D01*
Y598367D01*
G01Y598742D02*
X275558Y598992D01*
X275767Y599200D01*
X276017Y599283D01*
X276267Y599200D01*
X276475Y598992D01*
X276600Y598617D01*
X276558Y598242D01*
X276392Y597867D01*
G01X276600Y601550D02*
X276517Y601217D01*
X276308Y600967D01*
X276058Y600800D01*
X275725Y600675D01*
X275350Y600633D01*
X274975Y600675D01*
X274642Y600800D01*
X274392Y600967D01*
X274183Y601217D01*
X274100Y601550D01*
X274183Y601883D01*
X274392Y602133D01*
X274642Y602300D01*
X274975Y602425D01*
X275350Y602467D01*
X275725Y602425D01*
X276058Y602300D01*
X276308Y602133D01*
X276517Y601883D01*
X276600Y601550D01*
G01X284192Y593167D02*
X284317Y592917D01*
X284400Y592625D01*
Y592292D01*
X284275Y591917D01*
X284067Y591625D01*
X283817Y591417D01*
X283400Y591250D01*
X283025Y591208D01*
X282650Y591292D01*
X282400Y591417D01*
X282150Y591667D01*
X281983Y591958D01*
X281900Y592250D01*
Y592542D01*
X281983Y592833D01*
X282108Y593083D01*
X282275Y593292D01*
G01X282942Y594558D02*
X283233Y594850D01*
X283400Y595100D01*
X283483Y595433D01*
X283400Y595725D01*
X283233Y595933D01*
X282983Y596100D01*
X282692Y596142D01*
X282442Y596100D01*
X282192Y595933D01*
X281983Y595683D01*
X281900Y595392D01*
X281983Y595058D01*
X282233Y594767D01*
X282608Y594600D01*
X283025Y594558D01*
X283567Y594642D01*
X283858Y594767D01*
X284150Y594975D01*
X284358Y595267D01*
X284400Y595558D01*
X284317Y595850D01*
X284108Y596058D01*
G01X283983Y597658D02*
X284233Y597908D01*
X284358Y598200D01*
X284400Y598533D01*
X284317Y598950D01*
X284108Y599242D01*
X283858Y599325D01*
X283608Y599283D01*
X283400Y599117D01*
X282983Y598283D01*
X282692Y597908D01*
X282275Y597658D01*
X281900Y597575D01*
Y599325D01*
G01X282192Y600842D02*
X281983Y601133D01*
X281900Y601467D01*
X281983Y601800D01*
X282233Y602092D01*
X282608Y602300D01*
X282983Y602383D01*
X283442D01*
X283817Y602300D01*
X284150Y602092D01*
X284317Y601842D01*
X284400Y601550D01*
X284317Y601217D01*
X284150Y600967D01*
X283900Y600800D01*
X283567Y600717D01*
X283275Y600800D01*
X282983Y601008D01*
X282817Y601258D01*
X282775Y601550D01*
X282858Y601883D01*
X283067Y602133D01*
X283442Y602383D01*
G01X291992Y593167D02*
X292117Y592917D01*
X292200Y592625D01*
Y592292D01*
X292075Y591917D01*
X291867Y591625D01*
X291617Y591417D01*
X291200Y591250D01*
X290825Y591208D01*
X290450Y591292D01*
X290200Y591417D01*
X289950Y591667D01*
X289783Y591958D01*
X289700Y592250D01*
Y592542D01*
X289783Y592833D01*
X289908Y593083D01*
X290075Y593292D01*
G01X290742Y594558D02*
X291033Y594850D01*
X291200Y595100D01*
X291283Y595433D01*
X291200Y595725D01*
X291033Y595933D01*
X290783Y596100D01*
X290492Y596142D01*
X290242Y596100D01*
X289992Y595933D01*
X289783Y595683D01*
X289700Y595392D01*
X289783Y595058D01*
X290033Y594767D01*
X290408Y594600D01*
X290825Y594558D01*
X291367Y594642D01*
X291658Y594767D01*
X291950Y594975D01*
X292158Y595267D01*
X292200Y595558D01*
X292117Y595850D01*
X291908Y596058D01*
G01X291783Y597658D02*
X292033Y597908D01*
X292158Y598200D01*
X292200Y598533D01*
X292117Y598950D01*
X291908Y599242D01*
X291658Y599325D01*
X291408Y599283D01*
X291200Y599117D01*
X290783Y598283D01*
X290492Y597908D01*
X290075Y597658D01*
X289700Y597575D01*
Y599325D01*
G01Y601550D02*
X289742Y601842D01*
X289867Y602175D01*
X290075Y602383D01*
X290367Y602467D01*
X290658Y602383D01*
X290908Y602133D01*
X291033Y601758D01*
Y601342D01*
X291117Y601092D01*
X291325Y600883D01*
X291617Y600800D01*
X291908Y600925D01*
X292117Y601217D01*
X292200Y601550D01*
X292117Y601883D01*
X291908Y602175D01*
X291617Y602300D01*
X291325Y602217D01*
X291117Y602008D01*
X291033Y601758D01*
Y601342D01*
X290908Y600967D01*
X290658Y600717D01*
X290367Y600633D01*
X290075Y600717D01*
X289867Y600925D01*
X289742Y601258D01*
X289700Y601550D01*
G01X398705Y95774D02*
Y96774D01*
G01Y96274D02*
X396205D01*
G01Y95774D02*
Y96774D01*
G01Y99374D02*
X396247Y99041D01*
X396413Y98749D01*
X396663Y98499D01*
X396955Y98332D01*
X397288Y98249D01*
X397622D01*
X397955Y98332D01*
X398247Y98499D01*
X398497Y98749D01*
X398663Y99041D01*
X398705Y99374D01*
X398663Y99707D01*
X398497Y99999D01*
X398247Y100249D01*
X397955Y100416D01*
X397622Y100499D01*
X397288D01*
X396955Y100416D01*
X396663Y100249D01*
X396413Y99999D01*
X396247Y99707D01*
X396205Y99374D01*
G01Y102474D02*
X398705D01*
X398205Y101974D01*
G01X396205D02*
Y102974D01*
G01X419870Y135976D02*
Y59056D01*
X573070D01*
Y135976D01*
X419870D01*
G01X489065Y50394D02*
X489598Y50727D01*
X490198Y50927D01*
X490732D01*
X491265Y50727D01*
X491665Y50394D01*
X491865Y49927D01*
X491732Y49460D01*
X491398Y49060D01*
X490798Y48794D01*
X489998Y48660D01*
X489532Y48394D01*
X489332Y47927D01*
X489465Y47460D01*
X489798Y47127D01*
X490265Y46927D01*
X490732D01*
X491198Y47060D01*
X491598Y47394D01*
G01X495065Y50927D02*
Y46927D01*
G01X499665Y48260D02*
Y50927D01*
G01Y47194D02*
X499532Y47127D01*
Y46994D01*
X499665Y46927D01*
X499798Y46994D01*
Y47127D01*
X499665Y47194D01*
G01X504265Y46927D02*
Y50927D01*
G01X503332Y48260D02*
X505198D01*
G01X477437Y134376D02*
Y130376D01*
X479037D01*
X479570Y130576D01*
X479970Y131043D01*
X480103Y131576D01*
X479970Y132109D01*
X479637Y132509D01*
X479037Y132709D01*
X477437D01*
G01X482437Y134376D02*
Y131709D01*
G01Y132243D02*
X482770Y131976D01*
X483103Y131776D01*
X483570Y131709D01*
X483903Y131776D01*
X484303Y131976D01*
G01X486970Y132576D02*
X489103D01*
X488903Y132109D01*
X488570Y131843D01*
X488103Y131709D01*
X487637Y131776D01*
X487237Y131976D01*
X486970Y132443D01*
X486837Y132843D01*
Y133243D01*
X486970Y133643D01*
X487303Y134043D01*
X487703Y134309D01*
X488170Y134376D01*
X488637Y134243D01*
X489103Y133843D01*
G01X491570Y133909D02*
X491903Y134176D01*
X492370Y134376D01*
X492770D01*
X493170Y134243D01*
X493437Y134043D01*
X493570Y133776D01*
X493503Y133376D01*
X493237Y133176D01*
X492037Y132776D01*
X491770Y132309D01*
X491903Y131976D01*
X492170Y131776D01*
X492570Y131709D01*
X492970Y131776D01*
X493370Y131976D01*
G01X496170Y133909D02*
X496503Y134176D01*
X496970Y134376D01*
X497370D01*
X497770Y134243D01*
X498037Y134043D01*
X498170Y133776D01*
X498103Y133376D01*
X497837Y133176D01*
X496637Y132776D01*
X496370Y132309D01*
X496503Y131976D01*
X496770Y131776D01*
X497170Y131709D01*
X497570Y131776D01*
X497970Y131976D01*
G01X505103Y134376D02*
Y130376D01*
X507637D01*
G01X506703Y132309D02*
X505103D01*
G01X510970Y131709D02*
Y134376D01*
G01Y130643D02*
X510837Y130576D01*
Y130443D01*
X510970Y130376D01*
X511103Y130443D01*
Y130576D01*
X510970Y130643D01*
G01X515570Y130376D02*
Y134376D01*
G01X514637Y131709D02*
X516503D01*
G01X507718Y768700D02*
X507385Y768492D01*
X507010Y768367D01*
X506676D01*
X506343Y768492D01*
X506093Y768700D01*
X505968Y768992D01*
X506051Y769284D01*
X506260Y769534D01*
X506635Y769700D01*
X507135Y769784D01*
X507426Y769950D01*
X507551Y770242D01*
X507468Y770534D01*
X507260Y770742D01*
X506968Y770867D01*
X506676D01*
X506385Y770784D01*
X506135Y770575D01*
G01X502826Y770659D02*
X503076Y770784D01*
X503368Y770867D01*
X503701D01*
X504076Y770742D01*
X504368Y770534D01*
X504576Y770284D01*
X504743Y769867D01*
X504785Y769492D01*
X504701Y769117D01*
X504576Y768867D01*
X504326Y768617D01*
X504035Y768450D01*
X503743Y768367D01*
X503451D01*
X503160Y768450D01*
X502910Y768575D01*
X502701Y768742D01*
G01X501893Y770867D02*
X501310Y768367D01*
X500643Y770867D01*
X499976Y768367D01*
X499393Y770867D01*
G01X497543Y768367D02*
Y770867D01*
X498043Y770367D01*
G01Y768367D02*
X497043D01*
G01X664072Y665643D02*
Y668143D01*
X662156Y665643D01*
Y668143D01*
G01X660931D02*
Y666351D01*
X660764Y665976D01*
X660431Y665726D01*
X660014Y665643D01*
X659597Y665726D01*
X659264Y665976D01*
X659097Y666351D01*
Y668143D01*
G01X656914D02*
Y665643D01*
G01X657872Y668143D02*
X655956D01*
G01X653314Y665643D02*
Y668143D01*
X654856Y666351D01*
X652772D01*
G01X707213Y588105D02*
X682013D01*
Y626405D01*
X707213D01*
Y588105D01*
G01X697485Y631041D02*
Y633541D01*
X696651D01*
X696318Y633416D01*
X696068Y633249D01*
X695860Y632999D01*
X695693Y632708D01*
X695651Y632291D01*
X695693Y631874D01*
X695860Y631583D01*
X696068Y631333D01*
X696318Y631166D01*
X696651Y631041D01*
X697485D01*
G01X694385Y631541D02*
X694135Y631249D01*
X693801Y631083D01*
X693426Y631041D01*
X693093Y631083D01*
X692760Y631291D01*
X692551Y631541D01*
X692510Y631791D01*
X692593Y632083D01*
X692885Y632291D01*
X693176Y632374D01*
X693551D01*
G01X693176D02*
X692926Y632499D01*
X692718Y632708D01*
X692635Y632958D01*
X692718Y633208D01*
X692926Y633416D01*
X693301Y633541D01*
X693676Y633499D01*
X694051Y633333D01*
G01X690451Y631041D02*
X690368Y631583D01*
X690243Y632041D01*
X690076Y632458D01*
X689868Y632916D01*
X689535Y633541D01*
X691201D01*
G01X708298Y834634D02*
Y837134D01*
X706382Y834634D01*
Y837134D01*
G01X705157D02*
Y835342D01*
X704990Y834967D01*
X704657Y834717D01*
X704240Y834634D01*
X703823Y834717D01*
X703490Y834967D01*
X703323Y835342D01*
Y837134D01*
G01X701140D02*
Y834634D01*
G01X702098Y837134D02*
X700182D01*
G01X698123Y834634D02*
X698040Y835176D01*
X697915Y835634D01*
X697748Y836051D01*
X697540Y836509D01*
X697207Y837134D01*
X698873D01*
G01X705133Y873000D02*
Y875500D01*
X704092D01*
X703758Y875375D01*
X703550Y875208D01*
X703467Y874875D01*
X703550Y874542D01*
X703800Y874333D01*
X704092Y874208D01*
X705133D01*
G01X704092D02*
X703467Y873000D01*
G01X701200D02*
Y875500D01*
X701700Y875000D01*
G01Y873000D02*
X700700D01*
G01X698892Y875083D02*
X698642Y875333D01*
X698350Y875458D01*
X698017Y875500D01*
X697600Y875417D01*
X697308Y875208D01*
X697225Y874958D01*
X697267Y874708D01*
X697433Y874500D01*
X698267Y874083D01*
X698642Y873792D01*
X698892Y873375D01*
X698975Y873000D01*
X697225D01*
G01X695708Y873292D02*
X695417Y873083D01*
X695083Y873000D01*
X694750Y873083D01*
X694458Y873333D01*
X694250Y873708D01*
X694167Y874083D01*
Y874542D01*
X694250Y874917D01*
X694458Y875250D01*
X694708Y875417D01*
X695000Y875500D01*
X695333Y875417D01*
X695583Y875250D01*
X695750Y875000D01*
X695833Y874667D01*
X695750Y874375D01*
X695542Y874083D01*
X695292Y873917D01*
X695000Y873875D01*
X694667Y873958D01*
X694417Y874167D01*
X694167Y874542D01*
G01X691900Y873000D02*
Y875500D01*
X692400Y875000D01*
G01Y873000D02*
X691400D01*
G01X703483Y902000D02*
Y899500D01*
X701817D01*
G01X700258Y899792D02*
X699967Y899583D01*
X699633Y899500D01*
X699300Y899583D01*
X699008Y899833D01*
X698800Y900208D01*
X698717Y900583D01*
Y901042D01*
X698800Y901417D01*
X699008Y901750D01*
X699258Y901917D01*
X699550Y902000D01*
X699883Y901917D01*
X700133Y901750D01*
X700300Y901500D01*
X700383Y901167D01*
X700300Y900875D01*
X700092Y900583D01*
X699842Y900417D01*
X699550Y900375D01*
X699217Y900458D01*
X698967Y900667D01*
X698717Y901042D01*
G01X693600Y919967D02*
X696100D01*
Y921008D01*
X695975Y921342D01*
X695808Y921550D01*
X695475Y921633D01*
X695142Y921550D01*
X694933Y921300D01*
X694808Y921008D01*
Y919967D01*
G01Y921008D02*
X693600Y921633D01*
G01Y923900D02*
X696100D01*
X695600Y923400D01*
G01X693600D02*
Y924400D01*
G01X695683Y926208D02*
X695933Y926458D01*
X696058Y926750D01*
X696100Y927083D01*
X696017Y927500D01*
X695808Y927792D01*
X695558Y927875D01*
X695308Y927833D01*
X695100Y927667D01*
X694683Y926833D01*
X694392Y926458D01*
X693975Y926208D01*
X693600Y926125D01*
Y927875D01*
G01X693892Y929392D02*
X693683Y929683D01*
X693600Y930017D01*
X693683Y930350D01*
X693933Y930642D01*
X694308Y930850D01*
X694683Y930933D01*
X695142D01*
X695517Y930850D01*
X695850Y930642D01*
X696017Y930392D01*
X696100Y930100D01*
X696017Y929767D01*
X695850Y929517D01*
X695600Y929350D01*
X695267Y929267D01*
X694975Y929350D01*
X694683Y929558D01*
X694517Y929808D01*
X694475Y930100D01*
X694558Y930433D01*
X694767Y930683D01*
X695142Y930933D01*
G01X696100Y933200D02*
X696017Y932867D01*
X695808Y932617D01*
X695558Y932450D01*
X695225Y932325D01*
X694850Y932283D01*
X694475Y932325D01*
X694142Y932450D01*
X693892Y932617D01*
X693683Y932867D01*
X693600Y933200D01*
X693683Y933533D01*
X693892Y933783D01*
X694142Y933950D01*
X694475Y934075D01*
X694850Y934117D01*
X695225Y934075D01*
X695558Y933950D01*
X695808Y933783D01*
X696017Y933533D01*
X696100Y933200D01*
G01X698282Y919402D02*
Y927202D01*
G01X705282Y919402D02*
X698282D01*
G01Y932802D02*
X705282D01*
G01X698282Y926402D02*
Y932802D01*
G01X697392Y908267D02*
X697517Y908017D01*
X697600Y907725D01*
Y907392D01*
X697475Y907017D01*
X697267Y906725D01*
X697017Y906517D01*
X696600Y906350D01*
X696225Y906308D01*
X695850Y906392D01*
X695600Y906517D01*
X695350Y906767D01*
X695183Y907058D01*
X695100Y907350D01*
Y907642D01*
X695183Y907933D01*
X695308Y908183D01*
X695475Y908392D01*
G01X696142Y909658D02*
X696433Y909950D01*
X696600Y910200D01*
X696683Y910533D01*
X696600Y910825D01*
X696433Y911033D01*
X696183Y911200D01*
X695892Y911242D01*
X695642Y911200D01*
X695392Y911033D01*
X695183Y910783D01*
X695100Y910492D01*
X695183Y910158D01*
X695433Y909867D01*
X695808Y909700D01*
X696225Y909658D01*
X696767Y909742D01*
X697058Y909867D01*
X697350Y910075D01*
X697558Y910367D01*
X697600Y910658D01*
X697517Y910950D01*
X697308Y911158D01*
G01X695100Y913467D02*
X695642Y913550D01*
X696100Y913675D01*
X696517Y913842D01*
X696975Y914050D01*
X697600Y914383D01*
Y912717D01*
G01X695100Y916567D02*
X695642Y916650D01*
X696100Y916775D01*
X696517Y916942D01*
X696975Y917150D01*
X697600Y917483D01*
Y915817D01*
G01X702100Y877967D02*
X704600D01*
Y879008D01*
X704475Y879342D01*
X704308Y879550D01*
X703975Y879633D01*
X703642Y879550D01*
X703433Y879300D01*
X703308Y879008D01*
Y877967D01*
G01Y879008D02*
X702100Y879633D01*
G01Y881900D02*
X704600D01*
X704100Y881400D01*
G01X702100D02*
Y882400D01*
G01X704183Y884208D02*
X704433Y884458D01*
X704558Y884750D01*
X704600Y885083D01*
X704517Y885500D01*
X704308Y885792D01*
X704058Y885875D01*
X703808Y885833D01*
X703600Y885667D01*
X703183Y884833D01*
X702892Y884458D01*
X702475Y884208D01*
X702100Y884125D01*
Y885875D01*
G01X702392Y887392D02*
X702183Y887683D01*
X702100Y888017D01*
X702183Y888350D01*
X702433Y888642D01*
X702808Y888850D01*
X703183Y888933D01*
X703642D01*
X704017Y888850D01*
X704350Y888642D01*
X704517Y888392D01*
X704600Y888100D01*
X704517Y887767D01*
X704350Y887517D01*
X704100Y887350D01*
X703767Y887267D01*
X703475Y887350D01*
X703183Y887558D01*
X703017Y887808D01*
X702975Y888100D01*
X703058Y888433D01*
X703267Y888683D01*
X703642Y888933D01*
G01X704183Y890408D02*
X704433Y890658D01*
X704558Y890950D01*
X704600Y891283D01*
X704517Y891700D01*
X704308Y891992D01*
X704058Y892075D01*
X703808Y892033D01*
X703600Y891867D01*
X703183Y891033D01*
X702892Y890658D01*
X702475Y890408D01*
X702100Y890325D01*
Y892075D01*
G01X709711Y886900D02*
X713711D01*
Y879500D01*
G01X741200Y880000D02*
X745200D01*
Y872600D01*
G01X758716Y853489D02*
Y855989D01*
X757675D01*
X757341Y855864D01*
X757133Y855697D01*
X757050Y855364D01*
X757133Y855031D01*
X757383Y854822D01*
X757675Y854697D01*
X758716D01*
G01X757675D02*
X757050Y853489D01*
G01X754783D02*
Y855989D01*
X755283Y855489D01*
G01Y853489D02*
X754283D01*
G01X752475Y855572D02*
X752225Y855822D01*
X751933Y855947D01*
X751600Y855989D01*
X751183Y855906D01*
X750891Y855697D01*
X750808Y855447D01*
X750850Y855197D01*
X751016Y854989D01*
X751850Y854572D01*
X752225Y854281D01*
X752475Y853864D01*
X752558Y853489D01*
X750808D01*
G01X748583D02*
X748291Y853531D01*
X747958Y853656D01*
X747750Y853864D01*
X747666Y854156D01*
X747750Y854447D01*
X748000Y854697D01*
X748375Y854822D01*
X748791D01*
X749041Y854906D01*
X749250Y855114D01*
X749333Y855406D01*
X749208Y855697D01*
X748916Y855906D01*
X748583Y855989D01*
X748250Y855906D01*
X747958Y855697D01*
X747833Y855406D01*
X747916Y855114D01*
X748125Y854906D01*
X748375Y854822D01*
X748791D01*
X749166Y854697D01*
X749416Y854447D01*
X749500Y854156D01*
X749416Y853864D01*
X749208Y853656D01*
X748875Y853531D01*
X748583Y853489D01*
G01X746400Y853864D02*
X746150Y853656D01*
X745858Y853531D01*
X745483Y853489D01*
X745108Y853572D01*
X744816Y853739D01*
X744608Y854031D01*
X744566Y854364D01*
X744650Y854697D01*
X744858Y854906D01*
X745150Y855072D01*
X745441Y855114D01*
X745733Y855072D01*
X746108Y854906D01*
X745983Y855989D01*
X744858D01*
G01X751383Y866989D02*
Y862989D01*
X743983D01*
G01X735100Y843967D02*
X737600D01*
Y845008D01*
X737475Y845342D01*
X737308Y845550D01*
X736975Y845633D01*
X736642Y845550D01*
X736433Y845300D01*
X736308Y845008D01*
Y843967D01*
G01Y845008D02*
X735100Y845633D01*
G01Y847900D02*
X737600D01*
X737100Y847400D01*
G01X735100D02*
Y848400D01*
G01X737183Y850208D02*
X737433Y850458D01*
X737558Y850750D01*
X737600Y851083D01*
X737517Y851500D01*
X737308Y851792D01*
X737058Y851875D01*
X736808Y851833D01*
X736600Y851667D01*
X736183Y850833D01*
X735892Y850458D01*
X735475Y850208D01*
X735100Y850125D01*
Y851875D01*
G01Y854100D02*
X735142Y854392D01*
X735267Y854725D01*
X735475Y854933D01*
X735767Y855017D01*
X736058Y854933D01*
X736308Y854683D01*
X736433Y854308D01*
Y853892D01*
X736517Y853642D01*
X736725Y853433D01*
X737017Y853350D01*
X737308Y853475D01*
X737517Y853767D01*
X737600Y854100D01*
X737517Y854433D01*
X737308Y854725D01*
X737017Y854850D01*
X736725Y854767D01*
X736517Y854558D01*
X736433Y854308D01*
Y853892D01*
X736308Y853517D01*
X736058Y853267D01*
X735767Y853183D01*
X735475Y853267D01*
X735267Y853475D01*
X735142Y853808D01*
X735100Y854100D01*
G01X735600Y856283D02*
X735308Y856533D01*
X735142Y856867D01*
X735100Y857242D01*
X735142Y857575D01*
X735350Y857908D01*
X735600Y858117D01*
X735850Y858158D01*
X736142Y858075D01*
X736350Y857783D01*
X736433Y857492D01*
Y857117D01*
G01Y857492D02*
X736558Y857742D01*
X736767Y857950D01*
X737017Y858033D01*
X737267Y857950D01*
X737475Y857742D01*
X737600Y857367D01*
X737558Y856992D01*
X737392Y856617D01*
G01X739984Y863396D02*
X735984D01*
Y870796D01*
G01X719454Y878958D02*
Y874958D01*
X712054D01*
G01X727100Y843467D02*
X729600D01*
Y844508D01*
X729475Y844842D01*
X729308Y845050D01*
X728975Y845133D01*
X728642Y845050D01*
X728433Y844800D01*
X728308Y844508D01*
Y843467D01*
G01Y844508D02*
X727100Y845133D01*
G01Y847400D02*
X729600D01*
X729100Y846900D01*
G01X727100D02*
Y847900D01*
G01X729183Y849708D02*
X729433Y849958D01*
X729558Y850250D01*
X729600Y850583D01*
X729517Y851000D01*
X729308Y851292D01*
X729058Y851375D01*
X728808Y851333D01*
X728600Y851167D01*
X728183Y850333D01*
X727892Y849958D01*
X727475Y849708D01*
X727100Y849625D01*
Y851375D01*
G01Y853600D02*
X727142Y853892D01*
X727267Y854225D01*
X727475Y854433D01*
X727767Y854517D01*
X728058Y854433D01*
X728308Y854183D01*
X728433Y853808D01*
Y853392D01*
X728517Y853142D01*
X728725Y852933D01*
X729017Y852850D01*
X729308Y852975D01*
X729517Y853267D01*
X729600Y853600D01*
X729517Y853933D01*
X729308Y854225D01*
X729017Y854350D01*
X728725Y854267D01*
X728517Y854058D01*
X728433Y853808D01*
Y853392D01*
X728308Y853017D01*
X728058Y852767D01*
X727767Y852683D01*
X727475Y852767D01*
X727267Y852975D01*
X727142Y853308D01*
X727100Y853600D01*
G01Y856700D02*
X727142Y856992D01*
X727267Y857325D01*
X727475Y857533D01*
X727767Y857617D01*
X728058Y857533D01*
X728308Y857283D01*
X728433Y856908D01*
Y856492D01*
X728517Y856242D01*
X728725Y856033D01*
X729017Y855950D01*
X729308Y856075D01*
X729517Y856367D01*
X729600Y856700D01*
X729517Y857033D01*
X729308Y857325D01*
X729017Y857450D01*
X728725Y857367D01*
X728517Y857158D01*
X728433Y856908D01*
Y856492D01*
X728308Y856117D01*
X728058Y855867D01*
X727767Y855783D01*
X727475Y855867D01*
X727267Y856075D01*
X727142Y856408D01*
X727100Y856700D01*
G01X727182Y867902D02*
X731182D01*
Y860502D01*
G01X740617Y878000D02*
Y876208D01*
X740450Y875833D01*
X740117Y875583D01*
X739700Y875500D01*
X739283Y875583D01*
X738950Y875833D01*
X738783Y876208D01*
Y878000D01*
G01X737517Y876000D02*
X737267Y875708D01*
X736933Y875542D01*
X736558Y875500D01*
X736225Y875542D01*
X735892Y875750D01*
X735683Y876000D01*
X735642Y876250D01*
X735725Y876542D01*
X736017Y876750D01*
X736308Y876833D01*
X736683D01*
G01X736308D02*
X736058Y876958D01*
X735850Y877167D01*
X735767Y877417D01*
X735850Y877667D01*
X736058Y877875D01*
X736433Y878000D01*
X736808Y877958D01*
X737183Y877792D01*
G01X734417Y876000D02*
X734167Y875708D01*
X733833Y875542D01*
X733458Y875500D01*
X733125Y875542D01*
X732792Y875750D01*
X732583Y876000D01*
X732542Y876250D01*
X732625Y876542D01*
X732917Y876750D01*
X733208Y876833D01*
X733583D01*
G01X733208D02*
X732958Y876958D01*
X732750Y877167D01*
X732667Y877417D01*
X732750Y877667D01*
X732958Y877875D01*
X733333Y878000D01*
X733708Y877958D01*
X734083Y877792D01*
G01X725982Y878602D02*
X720982D01*
Y883602D01*
G01X739788Y887518D02*
X741788D01*
G01X721976Y885549D02*
X719976D01*
G01X714400Y865250D02*
X713567D01*
Y864500D01*
X713817Y864250D01*
X714108Y864083D01*
X714525Y864000D01*
X714942Y864083D01*
X715233Y864250D01*
X715483Y864500D01*
X715650Y864792D01*
X715733Y865125D01*
Y865417D01*
X715650Y865667D01*
X715483Y865958D01*
X715233Y866208D01*
X714983Y866375D01*
X714650Y866500D01*
X714358D01*
X714025Y866417D01*
X713775Y866250D01*
G01X711550Y864000D02*
Y866500D01*
X712050Y866000D01*
G01Y864000D02*
X711050D01*
G01X723800Y854500D02*
Y852000D01*
G01X724758Y854500D02*
X722842D01*
G01X721533Y852000D02*
Y854500D01*
X720533D01*
X720200Y854375D01*
X719950Y854083D01*
X719867Y853750D01*
X719950Y853417D01*
X720158Y853167D01*
X720533Y853042D01*
X721533D01*
G01X718392Y854083D02*
X718142Y854333D01*
X717850Y854458D01*
X717517Y854500D01*
X717100Y854417D01*
X716808Y854208D01*
X716725Y853958D01*
X716767Y853708D01*
X716933Y853500D01*
X717767Y853083D01*
X718142Y852792D01*
X718392Y852375D01*
X718475Y852000D01*
X716725D01*
G01X715292Y853042D02*
X715000Y853333D01*
X714750Y853500D01*
X714417Y853583D01*
X714125Y853500D01*
X713917Y853333D01*
X713750Y853083D01*
X713708Y852792D01*
X713750Y852542D01*
X713917Y852292D01*
X714167Y852083D01*
X714458Y852000D01*
X714792Y852083D01*
X715083Y852333D01*
X715250Y852708D01*
X715292Y853125D01*
X715208Y853667D01*
X715083Y853958D01*
X714875Y854250D01*
X714583Y854458D01*
X714292Y854500D01*
X714000Y854417D01*
X713792Y854208D01*
G01X711400Y854500D02*
X711733Y854417D01*
X711983Y854208D01*
X712150Y853958D01*
X712275Y853625D01*
X712317Y853250D01*
X712275Y852875D01*
X712150Y852542D01*
X711983Y852292D01*
X711733Y852083D01*
X711400Y852000D01*
X711067Y852083D01*
X710817Y852292D01*
X710650Y852542D01*
X710525Y852875D01*
X710483Y853250D01*
X710525Y853625D01*
X710650Y853958D01*
X710817Y854208D01*
X711067Y854417D01*
X711400Y854500D01*
G01X733392Y845267D02*
X733517Y845017D01*
X733600Y844725D01*
Y844392D01*
X733475Y844017D01*
X733267Y843725D01*
X733017Y843517D01*
X732600Y843350D01*
X732225Y843308D01*
X731850Y843392D01*
X731600Y843517D01*
X731350Y843767D01*
X731183Y844058D01*
X731100Y844350D01*
Y844642D01*
X731183Y844933D01*
X731308Y845183D01*
X731475Y845392D01*
G01X732142Y846658D02*
X732433Y846950D01*
X732600Y847200D01*
X732683Y847533D01*
X732600Y847825D01*
X732433Y848033D01*
X732183Y848200D01*
X731892Y848242D01*
X731642Y848200D01*
X731392Y848033D01*
X731183Y847783D01*
X731100Y847492D01*
X731183Y847158D01*
X731433Y846867D01*
X731808Y846700D01*
X732225Y846658D01*
X732767Y846742D01*
X733058Y846867D01*
X733350Y847075D01*
X733558Y847367D01*
X733600Y847658D01*
X733517Y847950D01*
X733308Y848158D01*
G01X731100Y850467D02*
X731642Y850550D01*
X732100Y850675D01*
X732517Y850842D01*
X732975Y851050D01*
X733600Y851383D01*
Y849717D01*
G01X732142Y852858D02*
X732433Y853150D01*
X732600Y853400D01*
X732683Y853733D01*
X732600Y854025D01*
X732433Y854233D01*
X732183Y854400D01*
X731892Y854442D01*
X731642Y854400D01*
X731392Y854233D01*
X731183Y853983D01*
X731100Y853692D01*
X731183Y853358D01*
X731433Y853067D01*
X731808Y852900D01*
X732225Y852858D01*
X732767Y852942D01*
X733058Y853067D01*
X733350Y853275D01*
X733558Y853567D01*
X733600Y853858D01*
X733517Y854150D01*
X733308Y854358D01*
G01X708392Y888767D02*
X708517Y888517D01*
X708600Y888225D01*
Y887892D01*
X708475Y887517D01*
X708267Y887225D01*
X708017Y887017D01*
X707600Y886850D01*
X707225Y886808D01*
X706850Y886892D01*
X706600Y887017D01*
X706350Y887267D01*
X706183Y887558D01*
X706100Y887850D01*
Y888142D01*
X706183Y888433D01*
X706308Y888683D01*
X706475Y888892D01*
G01X707142Y890158D02*
X707433Y890450D01*
X707600Y890700D01*
X707683Y891033D01*
X707600Y891325D01*
X707433Y891533D01*
X707183Y891700D01*
X706892Y891742D01*
X706642Y891700D01*
X706392Y891533D01*
X706183Y891283D01*
X706100Y890992D01*
X706183Y890658D01*
X706433Y890367D01*
X706808Y890200D01*
X707225Y890158D01*
X707767Y890242D01*
X708058Y890367D01*
X708350Y890575D01*
X708558Y890867D01*
X708600Y891158D01*
X708517Y891450D01*
X708308Y891658D01*
G01X706100Y894050D02*
X706142Y894342D01*
X706267Y894675D01*
X706475Y894883D01*
X706767Y894967D01*
X707058Y894883D01*
X707308Y894633D01*
X707433Y894258D01*
Y893842D01*
X707517Y893592D01*
X707725Y893383D01*
X708017Y893300D01*
X708308Y893425D01*
X708517Y893717D01*
X708600Y894050D01*
X708517Y894383D01*
X708308Y894675D01*
X708017Y894800D01*
X707725Y894717D01*
X707517Y894508D01*
X707433Y894258D01*
Y893842D01*
X707308Y893467D01*
X707058Y893217D01*
X706767Y893133D01*
X706475Y893217D01*
X706267Y893425D01*
X706142Y893758D01*
X706100Y894050D01*
G01Y897067D02*
X706642Y897150D01*
X707100Y897275D01*
X707517Y897442D01*
X707975Y897650D01*
X708600Y897983D01*
Y896317D01*
G01X756333Y860292D02*
X756583Y860417D01*
X756875Y860500D01*
X757208D01*
X757583Y860375D01*
X757875Y860167D01*
X758083Y859917D01*
X758250Y859500D01*
X758292Y859125D01*
X758208Y858750D01*
X758083Y858500D01*
X757833Y858250D01*
X757542Y858083D01*
X757250Y858000D01*
X756958D01*
X756667Y858083D01*
X756417Y858208D01*
X756208Y858375D01*
G01X754942Y859042D02*
X754650Y859333D01*
X754400Y859500D01*
X754067Y859583D01*
X753775Y859500D01*
X753567Y859333D01*
X753400Y859083D01*
X753358Y858792D01*
X753400Y858542D01*
X753567Y858292D01*
X753817Y858083D01*
X754108Y858000D01*
X754442Y858083D01*
X754733Y858333D01*
X754900Y858708D01*
X754942Y859125D01*
X754858Y859667D01*
X754733Y859958D01*
X754525Y860250D01*
X754233Y860458D01*
X753942Y860500D01*
X753650Y860417D01*
X753442Y860208D01*
G01X751133Y858000D02*
X751050Y858542D01*
X750925Y859000D01*
X750758Y859417D01*
X750550Y859875D01*
X750217Y860500D01*
X751883D01*
G01X748867Y858500D02*
X748617Y858208D01*
X748283Y858042D01*
X747908Y858000D01*
X747575Y858042D01*
X747242Y858250D01*
X747033Y858500D01*
X746992Y858750D01*
X747075Y859042D01*
X747367Y859250D01*
X747658Y859333D01*
X748033D01*
G01X747658D02*
X747408Y859458D01*
X747200Y859667D01*
X747117Y859917D01*
X747200Y860167D01*
X747408Y860375D01*
X747783Y860500D01*
X748158Y860458D01*
X748533Y860292D01*
G01X712333Y870292D02*
X712583Y870417D01*
X712875Y870500D01*
X713208D01*
X713583Y870375D01*
X713875Y870167D01*
X714083Y869917D01*
X714250Y869500D01*
X714292Y869125D01*
X714208Y868750D01*
X714083Y868500D01*
X713833Y868250D01*
X713542Y868083D01*
X713250Y868000D01*
X712958D01*
X712667Y868083D01*
X712417Y868208D01*
X712208Y868375D01*
G01X710942Y869042D02*
X710650Y869333D01*
X710400Y869500D01*
X710067Y869583D01*
X709775Y869500D01*
X709567Y869333D01*
X709400Y869083D01*
X709358Y868792D01*
X709400Y868542D01*
X709567Y868292D01*
X709817Y868083D01*
X710108Y868000D01*
X710442Y868083D01*
X710733Y868333D01*
X710900Y868708D01*
X710942Y869125D01*
X710858Y869667D01*
X710733Y869958D01*
X710525Y870250D01*
X710233Y870458D01*
X709942Y870500D01*
X709650Y870417D01*
X709442Y870208D01*
G01X707133Y868000D02*
X707050Y868542D01*
X706925Y869000D01*
X706758Y869417D01*
X706550Y869875D01*
X706217Y870500D01*
X707883D01*
G01X704867Y868375D02*
X704617Y868167D01*
X704325Y868042D01*
X703950Y868000D01*
X703575Y868083D01*
X703283Y868250D01*
X703075Y868542D01*
X703033Y868875D01*
X703117Y869208D01*
X703325Y869417D01*
X703617Y869583D01*
X703908Y869625D01*
X704200Y869583D01*
X704575Y869417D01*
X704450Y870500D01*
X703325D01*
G01X741392Y845767D02*
X741517Y845517D01*
X741600Y845225D01*
Y844892D01*
X741475Y844517D01*
X741267Y844225D01*
X741017Y844017D01*
X740600Y843850D01*
X740225Y843808D01*
X739850Y843892D01*
X739600Y844017D01*
X739350Y844267D01*
X739183Y844558D01*
X739100Y844850D01*
Y845142D01*
X739183Y845433D01*
X739308Y845683D01*
X739475Y845892D01*
G01X740142Y847158D02*
X740433Y847450D01*
X740600Y847700D01*
X740683Y848033D01*
X740600Y848325D01*
X740433Y848533D01*
X740183Y848700D01*
X739892Y848742D01*
X739642Y848700D01*
X739392Y848533D01*
X739183Y848283D01*
X739100Y847992D01*
X739183Y847658D01*
X739433Y847367D01*
X739808Y847200D01*
X740225Y847158D01*
X740767Y847242D01*
X741058Y847367D01*
X741350Y847575D01*
X741558Y847867D01*
X741600Y848158D01*
X741517Y848450D01*
X741308Y848658D01*
G01X739100Y850967D02*
X739642Y851050D01*
X740100Y851175D01*
X740517Y851342D01*
X740975Y851550D01*
X741600Y851883D01*
Y850217D01*
G01X739392Y853442D02*
X739183Y853733D01*
X739100Y854067D01*
X739183Y854400D01*
X739433Y854692D01*
X739808Y854900D01*
X740183Y854983D01*
X740642D01*
X741017Y854900D01*
X741350Y854692D01*
X741517Y854442D01*
X741600Y854150D01*
X741517Y853817D01*
X741350Y853567D01*
X741100Y853400D01*
X740767Y853317D01*
X740475Y853400D01*
X740183Y853608D01*
X740017Y853858D01*
X739975Y854150D01*
X740058Y854483D01*
X740267Y854733D01*
X740642Y854983D01*
G01X743682Y906102D02*
Y902102D01*
X736282D01*
G01X743983Y913989D02*
Y917989D01*
X751383D01*
G01X735782Y898402D02*
X740782D01*
Y893402D01*
G01X720982D02*
Y898402D01*
X725982D01*
G01X729898Y897408D02*
Y900408D01*
G01X706782Y934202D02*
Y898802D01*
X734782D01*
Y934202D01*
X706782D01*
G01X705282Y919402D02*
Y924602D01*
G01Y932802D02*
Y924102D01*
G01X710707Y952799D02*
X710832Y952549D01*
X710915Y952257D01*
Y951924D01*
X710790Y951549D01*
X710582Y951257D01*
X710332Y951049D01*
X709915Y950882D01*
X709540Y950840D01*
X709165Y950924D01*
X708915Y951049D01*
X708665Y951299D01*
X708498Y951590D01*
X708415Y951882D01*
Y952174D01*
X708498Y952465D01*
X708623Y952715D01*
X708790Y952924D01*
G01X709457Y954190D02*
X709748Y954482D01*
X709915Y954732D01*
X709998Y955065D01*
X709915Y955357D01*
X709748Y955565D01*
X709498Y955732D01*
X709207Y955774D01*
X708957Y955732D01*
X708707Y955565D01*
X708498Y955315D01*
X708415Y955024D01*
X708498Y954690D01*
X708748Y954399D01*
X709123Y954232D01*
X709540Y954190D01*
X710082Y954274D01*
X710373Y954399D01*
X710665Y954607D01*
X710873Y954899D01*
X710915Y955190D01*
X710832Y955482D01*
X710623Y955690D01*
G01X708415Y958082D02*
X708457Y958374D01*
X708582Y958707D01*
X708790Y958915D01*
X709082Y958999D01*
X709373Y958915D01*
X709623Y958665D01*
X709748Y958290D01*
Y957874D01*
X709832Y957624D01*
X710040Y957415D01*
X710332Y957332D01*
X710623Y957457D01*
X710832Y957749D01*
X710915Y958082D01*
X710832Y958415D01*
X710623Y958707D01*
X710332Y958832D01*
X710040Y958749D01*
X709832Y958540D01*
X709748Y958290D01*
Y957874D01*
X709623Y957499D01*
X709373Y957249D01*
X709082Y957165D01*
X708790Y957249D01*
X708582Y957457D01*
X708457Y957790D01*
X708415Y958082D01*
G01Y961682D02*
X710915D01*
X709123Y960140D01*
Y962224D01*
G01X714407Y952799D02*
X714532Y952549D01*
X714615Y952257D01*
Y951924D01*
X714490Y951549D01*
X714282Y951257D01*
X714032Y951049D01*
X713615Y950882D01*
X713240Y950840D01*
X712865Y950924D01*
X712615Y951049D01*
X712365Y951299D01*
X712198Y951590D01*
X712115Y951882D01*
Y952174D01*
X712198Y952465D01*
X712323Y952715D01*
X712490Y952924D01*
G01X713157Y954190D02*
X713448Y954482D01*
X713615Y954732D01*
X713698Y955065D01*
X713615Y955357D01*
X713448Y955565D01*
X713198Y955732D01*
X712907Y955774D01*
X712657Y955732D01*
X712407Y955565D01*
X712198Y955315D01*
X712115Y955024D01*
X712198Y954690D01*
X712448Y954399D01*
X712823Y954232D01*
X713240Y954190D01*
X713782Y954274D01*
X714073Y954399D01*
X714365Y954607D01*
X714573Y954899D01*
X714615Y955190D01*
X714532Y955482D01*
X714323Y955690D01*
G01X712115Y958082D02*
X712157Y958374D01*
X712282Y958707D01*
X712490Y958915D01*
X712782Y958999D01*
X713073Y958915D01*
X713323Y958665D01*
X713448Y958290D01*
Y957874D01*
X713532Y957624D01*
X713740Y957415D01*
X714032Y957332D01*
X714323Y957457D01*
X714532Y957749D01*
X714615Y958082D01*
X714532Y958415D01*
X714323Y958707D01*
X714032Y958832D01*
X713740Y958749D01*
X713532Y958540D01*
X713448Y958290D01*
Y957874D01*
X713323Y957499D01*
X713073Y957249D01*
X712782Y957165D01*
X712490Y957249D01*
X712282Y957457D01*
X712157Y957790D01*
X712115Y958082D01*
G01X712490Y960265D02*
X712282Y960515D01*
X712157Y960807D01*
X712115Y961182D01*
X712198Y961557D01*
X712365Y961849D01*
X712657Y962057D01*
X712990Y962099D01*
X713323Y962015D01*
X713532Y961807D01*
X713698Y961515D01*
X713740Y961224D01*
X713698Y960932D01*
X713532Y960557D01*
X714615Y960682D01*
Y961807D01*
G01X718107Y952799D02*
X718232Y952549D01*
X718315Y952257D01*
Y951924D01*
X718190Y951549D01*
X717982Y951257D01*
X717732Y951049D01*
X717315Y950882D01*
X716940Y950840D01*
X716565Y950924D01*
X716315Y951049D01*
X716065Y951299D01*
X715898Y951590D01*
X715815Y951882D01*
Y952174D01*
X715898Y952465D01*
X716023Y952715D01*
X716190Y952924D01*
G01X716857Y954190D02*
X717148Y954482D01*
X717315Y954732D01*
X717398Y955065D01*
X717315Y955357D01*
X717148Y955565D01*
X716898Y955732D01*
X716607Y955774D01*
X716357Y955732D01*
X716107Y955565D01*
X715898Y955315D01*
X715815Y955024D01*
X715898Y954690D01*
X716148Y954399D01*
X716523Y954232D01*
X716940Y954190D01*
X717482Y954274D01*
X717773Y954399D01*
X718065Y954607D01*
X718273Y954899D01*
X718315Y955190D01*
X718232Y955482D01*
X718023Y955690D01*
G01X715815Y958082D02*
X715857Y958374D01*
X715982Y958707D01*
X716190Y958915D01*
X716482Y958999D01*
X716773Y958915D01*
X717023Y958665D01*
X717148Y958290D01*
Y957874D01*
X717232Y957624D01*
X717440Y957415D01*
X717732Y957332D01*
X718023Y957457D01*
X718232Y957749D01*
X718315Y958082D01*
X718232Y958415D01*
X718023Y958707D01*
X717732Y958832D01*
X717440Y958749D01*
X717232Y958540D01*
X717148Y958290D01*
Y957874D01*
X717023Y957499D01*
X716773Y957249D01*
X716482Y957165D01*
X716190Y957249D01*
X715982Y957457D01*
X715857Y957790D01*
X715815Y958082D01*
G01X716857Y960390D02*
X717148Y960682D01*
X717315Y960932D01*
X717398Y961265D01*
X717315Y961557D01*
X717148Y961765D01*
X716898Y961932D01*
X716607Y961974D01*
X716357Y961932D01*
X716107Y961765D01*
X715898Y961515D01*
X715815Y961224D01*
X715898Y960890D01*
X716148Y960599D01*
X716523Y960432D01*
X716940Y960390D01*
X717482Y960474D01*
X717773Y960599D01*
X718065Y960807D01*
X718273Y961099D01*
X718315Y961390D01*
X718232Y961682D01*
X718023Y961890D01*
G01X707007Y952799D02*
X707132Y952549D01*
X707215Y952257D01*
Y951924D01*
X707090Y951549D01*
X706882Y951257D01*
X706632Y951049D01*
X706215Y950882D01*
X705840Y950840D01*
X705465Y950924D01*
X705215Y951049D01*
X704965Y951299D01*
X704798Y951590D01*
X704715Y951882D01*
Y952174D01*
X704798Y952465D01*
X704923Y952715D01*
X705090Y952924D01*
G01X705757Y954190D02*
X706048Y954482D01*
X706215Y954732D01*
X706298Y955065D01*
X706215Y955357D01*
X706048Y955565D01*
X705798Y955732D01*
X705507Y955774D01*
X705257Y955732D01*
X705007Y955565D01*
X704798Y955315D01*
X704715Y955024D01*
X704798Y954690D01*
X705048Y954399D01*
X705423Y954232D01*
X705840Y954190D01*
X706382Y954274D01*
X706673Y954399D01*
X706965Y954607D01*
X707173Y954899D01*
X707215Y955190D01*
X707132Y955482D01*
X706923Y955690D01*
G01X704715Y958082D02*
X704757Y958374D01*
X704882Y958707D01*
X705090Y958915D01*
X705382Y958999D01*
X705673Y958915D01*
X705923Y958665D01*
X706048Y958290D01*
Y957874D01*
X706132Y957624D01*
X706340Y957415D01*
X706632Y957332D01*
X706923Y957457D01*
X707132Y957749D01*
X707215Y958082D01*
X707132Y958415D01*
X706923Y958707D01*
X706632Y958832D01*
X706340Y958749D01*
X706132Y958540D01*
X706048Y958290D01*
Y957874D01*
X705923Y957499D01*
X705673Y957249D01*
X705382Y957165D01*
X705090Y957249D01*
X704882Y957457D01*
X704757Y957790D01*
X704715Y958082D01*
G01X707215Y961182D02*
X707132Y960849D01*
X706923Y960599D01*
X706673Y960432D01*
X706340Y960307D01*
X705965Y960265D01*
X705590Y960307D01*
X705257Y960432D01*
X705007Y960599D01*
X704798Y960849D01*
X704715Y961182D01*
X704798Y961515D01*
X705007Y961765D01*
X705257Y961932D01*
X705590Y962057D01*
X705965Y962099D01*
X706340Y962057D01*
X706673Y961932D01*
X706923Y961765D01*
X707132Y961515D01*
X707215Y961182D01*
G01X770400Y871567D02*
X772900D01*
Y872608D01*
X772775Y872942D01*
X772608Y873150D01*
X772275Y873233D01*
X771942Y873150D01*
X771733Y872900D01*
X771608Y872608D01*
Y871567D01*
G01Y872608D02*
X770400Y873233D01*
G01Y875500D02*
X772900D01*
X772400Y875000D01*
G01X770400D02*
Y876000D01*
G01X772483Y877808D02*
X772733Y878058D01*
X772858Y878350D01*
X772900Y878683D01*
X772817Y879100D01*
X772608Y879392D01*
X772358Y879475D01*
X772108Y879433D01*
X771900Y879267D01*
X771483Y878433D01*
X771192Y878058D01*
X770775Y877808D01*
X770400Y877725D01*
Y879475D01*
G01Y881700D02*
X770442Y881992D01*
X770567Y882325D01*
X770775Y882533D01*
X771067Y882617D01*
X771358Y882533D01*
X771608Y882283D01*
X771733Y881908D01*
Y881492D01*
X771817Y881242D01*
X772025Y881033D01*
X772317Y880950D01*
X772608Y881075D01*
X772817Y881367D01*
X772900Y881700D01*
X772817Y882033D01*
X772608Y882325D01*
X772317Y882450D01*
X772025Y882367D01*
X771817Y882158D01*
X771733Y881908D01*
Y881492D01*
X771608Y881117D01*
X771358Y880867D01*
X771067Y880783D01*
X770775Y880867D01*
X770567Y881075D01*
X770442Y881408D01*
X770400Y881700D01*
G01X771442Y884008D02*
X771733Y884300D01*
X771900Y884550D01*
X771983Y884883D01*
X771900Y885175D01*
X771733Y885383D01*
X771483Y885550D01*
X771192Y885592D01*
X770942Y885550D01*
X770692Y885383D01*
X770483Y885133D01*
X770400Y884842D01*
X770483Y884508D01*
X770733Y884217D01*
X771108Y884050D01*
X771525Y884008D01*
X772067Y884092D01*
X772358Y884217D01*
X772650Y884425D01*
X772858Y884717D01*
X772900Y885008D01*
X772817Y885300D01*
X772608Y885508D01*
G01X784100Y872967D02*
X786600D01*
Y874008D01*
X786475Y874342D01*
X786308Y874550D01*
X785975Y874633D01*
X785642Y874550D01*
X785433Y874300D01*
X785308Y874008D01*
Y872967D01*
G01Y874008D02*
X784100Y874633D01*
G01Y876900D02*
X786600D01*
X786100Y876400D01*
G01X784100D02*
Y877400D01*
G01X786183Y879208D02*
X786433Y879458D01*
X786558Y879750D01*
X786600Y880083D01*
X786517Y880500D01*
X786308Y880792D01*
X786058Y880875D01*
X785808Y880833D01*
X785600Y880667D01*
X785183Y879833D01*
X784892Y879458D01*
X784475Y879208D01*
X784100Y879125D01*
Y880875D01*
G01Y883100D02*
X784142Y883392D01*
X784267Y883725D01*
X784475Y883933D01*
X784767Y884017D01*
X785058Y883933D01*
X785308Y883683D01*
X785433Y883308D01*
Y882892D01*
X785517Y882642D01*
X785725Y882433D01*
X786017Y882350D01*
X786308Y882475D01*
X786517Y882767D01*
X786600Y883100D01*
X786517Y883433D01*
X786308Y883725D01*
X786017Y883850D01*
X785725Y883767D01*
X785517Y883558D01*
X785433Y883308D01*
Y882892D01*
X785308Y882517D01*
X785058Y882267D01*
X784767Y882183D01*
X784475Y882267D01*
X784267Y882475D01*
X784142Y882808D01*
X784100Y883100D01*
G01X786183Y885408D02*
X786433Y885658D01*
X786558Y885950D01*
X786600Y886283D01*
X786517Y886700D01*
X786308Y886992D01*
X786058Y887075D01*
X785808Y887033D01*
X785600Y886867D01*
X785183Y886033D01*
X784892Y885658D01*
X784475Y885408D01*
X784100Y885325D01*
Y887075D01*
G01X767818Y891698D02*
X759818D01*
Y874098D01*
X767818D01*
Y891698D01*
G01X776633Y859000D02*
Y861500D01*
X775592D01*
X775258Y861375D01*
X775050Y861208D01*
X774967Y860875D01*
X775050Y860542D01*
X775300Y860333D01*
X775592Y860208D01*
X776633D01*
G01X775592D02*
X774967Y859000D01*
G01X772700D02*
Y861500D01*
X773200Y861000D01*
G01Y859000D02*
X772200D01*
G01X770392Y861083D02*
X770142Y861333D01*
X769850Y861458D01*
X769517Y861500D01*
X769100Y861417D01*
X768808Y861208D01*
X768725Y860958D01*
X768767Y860708D01*
X768933Y860500D01*
X769767Y860083D01*
X770142Y859792D01*
X770392Y859375D01*
X770475Y859000D01*
X768725D01*
G01X766500D02*
X766208Y859042D01*
X765875Y859167D01*
X765667Y859375D01*
X765583Y859667D01*
X765667Y859958D01*
X765917Y860208D01*
X766292Y860333D01*
X766708D01*
X766958Y860417D01*
X767167Y860625D01*
X767250Y860917D01*
X767125Y861208D01*
X766833Y861417D01*
X766500Y861500D01*
X766167Y861417D01*
X765875Y861208D01*
X765750Y860917D01*
X765833Y860625D01*
X766042Y860417D01*
X766292Y860333D01*
X766708D01*
X767083Y860208D01*
X767333Y859958D01*
X767417Y859667D01*
X767333Y859375D01*
X767125Y859167D01*
X766792Y859042D01*
X766500Y859000D01*
G01X762900D02*
Y861500D01*
X764442Y859708D01*
X762358D01*
G01X779700Y873067D02*
X782200D01*
Y874108D01*
X782075Y874442D01*
X781908Y874650D01*
X781575Y874733D01*
X781242Y874650D01*
X781033Y874400D01*
X780908Y874108D01*
Y873067D01*
G01Y874108D02*
X779700Y874733D01*
G01Y877000D02*
X782200D01*
X781700Y876500D01*
G01X779700D02*
Y877500D01*
G01X781783Y879308D02*
X782033Y879558D01*
X782158Y879850D01*
X782200Y880183D01*
X782117Y880600D01*
X781908Y880892D01*
X781658Y880975D01*
X781408Y880933D01*
X781200Y880767D01*
X780783Y879933D01*
X780492Y879558D01*
X780075Y879308D01*
X779700Y879225D01*
Y880975D01*
G01Y883200D02*
X779742Y883492D01*
X779867Y883825D01*
X780075Y884033D01*
X780367Y884117D01*
X780658Y884033D01*
X780908Y883783D01*
X781033Y883408D01*
Y882992D01*
X781117Y882742D01*
X781325Y882533D01*
X781617Y882450D01*
X781908Y882575D01*
X782117Y882867D01*
X782200Y883200D01*
X782117Y883533D01*
X781908Y883825D01*
X781617Y883950D01*
X781325Y883867D01*
X781117Y883658D01*
X781033Y883408D01*
Y882992D01*
X780908Y882617D01*
X780658Y882367D01*
X780367Y882283D01*
X780075Y882367D01*
X779867Y882575D01*
X779742Y882908D01*
X779700Y883200D01*
G01Y886300D02*
X782200D01*
X781700Y885800D01*
G01X779700D02*
Y886800D01*
G01X777581Y874550D02*
X777706Y874300D01*
X777789Y874008D01*
Y873675D01*
X777664Y873300D01*
X777456Y873008D01*
X777206Y872800D01*
X776789Y872633D01*
X776414Y872591D01*
X776039Y872675D01*
X775789Y872800D01*
X775539Y873050D01*
X775372Y873341D01*
X775289Y873633D01*
Y873925D01*
X775372Y874216D01*
X775497Y874466D01*
X775664Y874675D01*
G01X776331Y875941D02*
X776622Y876233D01*
X776789Y876483D01*
X776872Y876816D01*
X776789Y877108D01*
X776622Y877316D01*
X776372Y877483D01*
X776081Y877525D01*
X775831Y877483D01*
X775581Y877316D01*
X775372Y877066D01*
X775289Y876775D01*
X775372Y876441D01*
X775622Y876150D01*
X775997Y875983D01*
X776414Y875941D01*
X776956Y876025D01*
X777247Y876150D01*
X777539Y876358D01*
X777747Y876650D01*
X777789Y876941D01*
X777706Y877233D01*
X777497Y877441D01*
G01X776331Y879041D02*
X776622Y879333D01*
X776789Y879583D01*
X776872Y879916D01*
X776789Y880208D01*
X776622Y880416D01*
X776372Y880583D01*
X776081Y880625D01*
X775831Y880583D01*
X775581Y880416D01*
X775372Y880166D01*
X775289Y879875D01*
X775372Y879541D01*
X775622Y879250D01*
X775997Y879083D01*
X776414Y879041D01*
X776956Y879125D01*
X777247Y879250D01*
X777539Y879458D01*
X777747Y879750D01*
X777789Y880041D01*
X777706Y880333D01*
X777497Y880541D01*
G01X775581Y882225D02*
X775372Y882516D01*
X775289Y882850D01*
X775372Y883183D01*
X775622Y883475D01*
X775997Y883683D01*
X776372Y883766D01*
X776831D01*
X777206Y883683D01*
X777539Y883475D01*
X777706Y883225D01*
X777789Y882933D01*
X777706Y882600D01*
X777539Y882350D01*
X777289Y882183D01*
X776956Y882100D01*
X776664Y882183D01*
X776372Y882391D01*
X776206Y882641D01*
X776164Y882933D01*
X776247Y883266D01*
X776456Y883516D01*
X776831Y883766D01*
G01X784133Y903500D02*
Y906000D01*
X783092D01*
X782758Y905875D01*
X782550Y905708D01*
X782467Y905375D01*
X782550Y905042D01*
X782800Y904833D01*
X783092Y904708D01*
X784133D01*
G01X783092D02*
X782467Y903500D01*
G01X780200D02*
Y906000D01*
X780700Y905500D01*
G01Y903500D02*
X779700D01*
G01X777892Y905583D02*
X777642Y905833D01*
X777350Y905958D01*
X777017Y906000D01*
X776600Y905917D01*
X776308Y905708D01*
X776225Y905458D01*
X776267Y905208D01*
X776433Y905000D01*
X777267Y904583D01*
X777642Y904292D01*
X777892Y903875D01*
X777975Y903500D01*
X776225D01*
G01X774000D02*
X773708Y903542D01*
X773375Y903667D01*
X773167Y903875D01*
X773083Y904167D01*
X773167Y904458D01*
X773417Y904708D01*
X773792Y904833D01*
X774208D01*
X774458Y904917D01*
X774667Y905125D01*
X774750Y905417D01*
X774625Y905708D01*
X774333Y905917D01*
X774000Y906000D01*
X773667Y905917D01*
X773375Y905708D01*
X773250Y905417D01*
X773333Y905125D01*
X773542Y904917D01*
X773792Y904833D01*
X774208D01*
X774583Y904708D01*
X774833Y904458D01*
X774917Y904167D01*
X774833Y903875D01*
X774625Y903667D01*
X774292Y903542D01*
X774000Y903500D01*
G01X770983D02*
X770900Y904042D01*
X770775Y904500D01*
X770608Y904917D01*
X770400Y905375D01*
X770067Y906000D01*
X771733D01*
G01X768216Y914489D02*
Y916989D01*
X767175D01*
X766841Y916864D01*
X766633Y916697D01*
X766550Y916364D01*
X766633Y916031D01*
X766883Y915822D01*
X767175Y915697D01*
X768216D01*
G01X767175D02*
X766550Y914489D01*
G01X764283D02*
Y916989D01*
X764783Y916489D01*
G01Y914489D02*
X763783D01*
G01X761975Y916572D02*
X761725Y916822D01*
X761433Y916947D01*
X761100Y916989D01*
X760683Y916906D01*
X760391Y916697D01*
X760308Y916447D01*
X760350Y916197D01*
X760516Y915989D01*
X761350Y915572D01*
X761725Y915281D01*
X761975Y914864D01*
X762058Y914489D01*
X760308D01*
G01X758083D02*
X757791Y914531D01*
X757458Y914656D01*
X757250Y914864D01*
X757166Y915156D01*
X757250Y915447D01*
X757500Y915697D01*
X757875Y915822D01*
X758291D01*
X758541Y915906D01*
X758750Y916114D01*
X758833Y916406D01*
X758708Y916697D01*
X758416Y916906D01*
X758083Y916989D01*
X757750Y916906D01*
X757458Y916697D01*
X757333Y916406D01*
X757416Y916114D01*
X757625Y915906D01*
X757875Y915822D01*
X758291D01*
X758666Y915697D01*
X758916Y915447D01*
X759000Y915156D01*
X758916Y914864D01*
X758708Y914656D01*
X758375Y914531D01*
X758083Y914489D01*
G01X755691Y914781D02*
X755400Y914572D01*
X755066Y914489D01*
X754733Y914572D01*
X754441Y914822D01*
X754233Y915197D01*
X754150Y915572D01*
Y916031D01*
X754233Y916406D01*
X754441Y916739D01*
X754691Y916906D01*
X754983Y916989D01*
X755316Y916906D01*
X755566Y916739D01*
X755733Y916489D01*
X755816Y916156D01*
X755733Y915864D01*
X755525Y915572D01*
X755275Y915406D01*
X754983Y915364D01*
X754650Y915447D01*
X754400Y915656D01*
X754150Y916031D01*
G01X757900Y925250D02*
X757067D01*
Y924500D01*
X757317Y924250D01*
X757608Y924083D01*
X758025Y924000D01*
X758442Y924083D01*
X758733Y924250D01*
X758983Y924500D01*
X759150Y924792D01*
X759233Y925125D01*
Y925417D01*
X759150Y925667D01*
X758983Y925958D01*
X758733Y926208D01*
X758483Y926375D01*
X758150Y926500D01*
X757858D01*
X757525Y926417D01*
X757275Y926250D01*
G01X755842Y926083D02*
X755592Y926333D01*
X755300Y926458D01*
X754967Y926500D01*
X754550Y926417D01*
X754258Y926208D01*
X754175Y925958D01*
X754217Y925708D01*
X754383Y925500D01*
X755217Y925083D01*
X755592Y924792D01*
X755842Y924375D01*
X755925Y924000D01*
X754175D01*
G01X765815Y939894D02*
X766065Y940019D01*
X766357Y940102D01*
X766690D01*
X767065Y939977D01*
X767357Y939769D01*
X767565Y939519D01*
X767732Y939102D01*
X767774Y938727D01*
X767690Y938352D01*
X767565Y938102D01*
X767315Y937852D01*
X767024Y937685D01*
X766732Y937602D01*
X766440D01*
X766149Y937685D01*
X765899Y937810D01*
X765690Y937977D01*
G01X764424Y938644D02*
X764132Y938935D01*
X763882Y939102D01*
X763549Y939185D01*
X763257Y939102D01*
X763049Y938935D01*
X762882Y938685D01*
X762840Y938394D01*
X762882Y938144D01*
X763049Y937894D01*
X763299Y937685D01*
X763590Y937602D01*
X763924Y937685D01*
X764215Y937935D01*
X764382Y938310D01*
X764424Y938727D01*
X764340Y939269D01*
X764215Y939560D01*
X764007Y939852D01*
X763715Y940060D01*
X763424Y940102D01*
X763132Y940019D01*
X762924Y939810D01*
G01X760532Y937602D02*
X760240Y937644D01*
X759907Y937769D01*
X759699Y937977D01*
X759615Y938269D01*
X759699Y938560D01*
X759949Y938810D01*
X760324Y938935D01*
X760740D01*
X760990Y939019D01*
X761199Y939227D01*
X761282Y939519D01*
X761157Y939810D01*
X760865Y940019D01*
X760532Y940102D01*
X760199Y940019D01*
X759907Y939810D01*
X759782Y939519D01*
X759865Y939227D01*
X760074Y939019D01*
X760324Y938935D01*
X760740D01*
X761115Y938810D01*
X761365Y938560D01*
X761449Y938269D01*
X761365Y937977D01*
X761157Y937769D01*
X760824Y937644D01*
X760532Y937602D01*
G01X758224Y939685D02*
X757974Y939935D01*
X757682Y940060D01*
X757349Y940102D01*
X756932Y940019D01*
X756640Y939810D01*
X756557Y939560D01*
X756599Y939310D01*
X756765Y939102D01*
X757599Y938685D01*
X757974Y938394D01*
X758224Y937977D01*
X758307Y937602D01*
X756557D01*
G01X765815Y932094D02*
X766065Y932219D01*
X766357Y932302D01*
X766690D01*
X767065Y932177D01*
X767357Y931969D01*
X767565Y931719D01*
X767732Y931302D01*
X767774Y930927D01*
X767690Y930552D01*
X767565Y930302D01*
X767315Y930052D01*
X767024Y929885D01*
X766732Y929802D01*
X766440D01*
X766149Y929885D01*
X765899Y930010D01*
X765690Y930177D01*
G01X764424Y930844D02*
X764132Y931135D01*
X763882Y931302D01*
X763549Y931385D01*
X763257Y931302D01*
X763049Y931135D01*
X762882Y930885D01*
X762840Y930594D01*
X762882Y930344D01*
X763049Y930094D01*
X763299Y929885D01*
X763590Y929802D01*
X763924Y929885D01*
X764215Y930135D01*
X764382Y930510D01*
X764424Y930927D01*
X764340Y931469D01*
X764215Y931760D01*
X764007Y932052D01*
X763715Y932260D01*
X763424Y932302D01*
X763132Y932219D01*
X762924Y932010D01*
G01X760532Y929802D02*
X760240Y929844D01*
X759907Y929969D01*
X759699Y930177D01*
X759615Y930469D01*
X759699Y930760D01*
X759949Y931010D01*
X760324Y931135D01*
X760740D01*
X760990Y931219D01*
X761199Y931427D01*
X761282Y931719D01*
X761157Y932010D01*
X760865Y932219D01*
X760532Y932302D01*
X760199Y932219D01*
X759907Y932010D01*
X759782Y931719D01*
X759865Y931427D01*
X760074Y931219D01*
X760324Y931135D01*
X760740D01*
X761115Y931010D01*
X761365Y930760D01*
X761449Y930469D01*
X761365Y930177D01*
X761157Y929969D01*
X760824Y929844D01*
X760532Y929802D01*
G01X758349Y930302D02*
X758099Y930010D01*
X757765Y929844D01*
X757390Y929802D01*
X757057Y929844D01*
X756724Y930052D01*
X756515Y930302D01*
X756474Y930552D01*
X756557Y930844D01*
X756849Y931052D01*
X757140Y931135D01*
X757515D01*
G01X757140D02*
X756890Y931260D01*
X756682Y931469D01*
X756599Y931719D01*
X756682Y931969D01*
X756890Y932177D01*
X757265Y932302D01*
X757640Y932260D01*
X758015Y932094D01*
G01X780892Y892267D02*
X781017Y892017D01*
X781100Y891725D01*
Y891392D01*
X780975Y891017D01*
X780767Y890725D01*
X780517Y890517D01*
X780100Y890350D01*
X779725Y890308D01*
X779350Y890392D01*
X779100Y890517D01*
X778850Y890767D01*
X778683Y891058D01*
X778600Y891350D01*
Y891642D01*
X778683Y891933D01*
X778808Y892183D01*
X778975Y892392D01*
G01X779642Y893658D02*
X779933Y893950D01*
X780100Y894200D01*
X780183Y894533D01*
X780100Y894825D01*
X779933Y895033D01*
X779683Y895200D01*
X779392Y895242D01*
X779142Y895200D01*
X778892Y895033D01*
X778683Y894783D01*
X778600Y894492D01*
X778683Y894158D01*
X778933Y893867D01*
X779308Y893700D01*
X779725Y893658D01*
X780267Y893742D01*
X780558Y893867D01*
X780850Y894075D01*
X781058Y894367D01*
X781100Y894658D01*
X781017Y894950D01*
X780808Y895158D01*
G01X778600Y897467D02*
X779142Y897550D01*
X779600Y897675D01*
X780017Y897842D01*
X780475Y898050D01*
X781100Y898383D01*
Y896717D01*
G01X778600Y900650D02*
X781100D01*
X780600Y900150D01*
G01X778600D02*
Y901150D01*
G01X776892Y892267D02*
X777017Y892017D01*
X777100Y891725D01*
Y891392D01*
X776975Y891017D01*
X776767Y890725D01*
X776517Y890517D01*
X776100Y890350D01*
X775725Y890308D01*
X775350Y890392D01*
X775100Y890517D01*
X774850Y890767D01*
X774683Y891058D01*
X774600Y891350D01*
Y891642D01*
X774683Y891933D01*
X774808Y892183D01*
X774975Y892392D01*
G01X775642Y893658D02*
X775933Y893950D01*
X776100Y894200D01*
X776183Y894533D01*
X776100Y894825D01*
X775933Y895033D01*
X775683Y895200D01*
X775392Y895242D01*
X775142Y895200D01*
X774892Y895033D01*
X774683Y894783D01*
X774600Y894492D01*
X774683Y894158D01*
X774933Y893867D01*
X775308Y893700D01*
X775725Y893658D01*
X776267Y893742D01*
X776558Y893867D01*
X776850Y894075D01*
X777058Y894367D01*
X777100Y894658D01*
X777017Y894950D01*
X776808Y895158D01*
G01X774600Y897467D02*
X775142Y897550D01*
X775600Y897675D01*
X776017Y897842D01*
X776475Y898050D01*
X777100Y898383D01*
Y896717D01*
G01X776683Y899858D02*
X776933Y900108D01*
X777058Y900400D01*
X777100Y900733D01*
X777017Y901150D01*
X776808Y901442D01*
X776558Y901525D01*
X776308Y901483D01*
X776100Y901317D01*
X775683Y900483D01*
X775392Y900108D01*
X774975Y899858D01*
X774600Y899775D01*
Y901525D01*
G01X772892Y909267D02*
X773017Y909017D01*
X773100Y908725D01*
Y908392D01*
X772975Y908017D01*
X772767Y907725D01*
X772517Y907517D01*
X772100Y907350D01*
X771725Y907308D01*
X771350Y907392D01*
X771100Y907517D01*
X770850Y907767D01*
X770683Y908058D01*
X770600Y908350D01*
Y908642D01*
X770683Y908933D01*
X770808Y909183D01*
X770975Y909392D01*
G01X771642Y910658D02*
X771933Y910950D01*
X772100Y911200D01*
X772183Y911533D01*
X772100Y911825D01*
X771933Y912033D01*
X771683Y912200D01*
X771392Y912242D01*
X771142Y912200D01*
X770892Y912033D01*
X770683Y911783D01*
X770600Y911492D01*
X770683Y911158D01*
X770933Y910867D01*
X771308Y910700D01*
X771725Y910658D01*
X772267Y910742D01*
X772558Y910867D01*
X772850Y911075D01*
X773058Y911367D01*
X773100Y911658D01*
X773017Y911950D01*
X772808Y912158D01*
G01X770600Y914467D02*
X771142Y914550D01*
X771600Y914675D01*
X772017Y914842D01*
X772475Y915050D01*
X773100Y915383D01*
Y913717D01*
G01X770600Y918150D02*
X773100D01*
X771308Y916608D01*
Y918692D01*
G01X765233Y922158D02*
X765483Y922283D01*
X765775Y922366D01*
X766108D01*
X766483Y922241D01*
X766775Y922033D01*
X766983Y921783D01*
X767150Y921366D01*
X767192Y920991D01*
X767108Y920616D01*
X766983Y920366D01*
X766733Y920116D01*
X766442Y919949D01*
X766150Y919866D01*
X765858D01*
X765567Y919949D01*
X765317Y920074D01*
X765108Y920241D01*
G01X763842Y920908D02*
X763550Y921199D01*
X763300Y921366D01*
X762967Y921449D01*
X762675Y921366D01*
X762467Y921199D01*
X762300Y920949D01*
X762258Y920658D01*
X762300Y920408D01*
X762467Y920158D01*
X762717Y919949D01*
X763008Y919866D01*
X763342Y919949D01*
X763633Y920199D01*
X763800Y920574D01*
X763842Y920991D01*
X763758Y921533D01*
X763633Y921824D01*
X763425Y922116D01*
X763133Y922324D01*
X762842Y922366D01*
X762550Y922283D01*
X762342Y922074D01*
G01X760033Y919866D02*
X759950Y920408D01*
X759825Y920866D01*
X759658Y921283D01*
X759450Y921741D01*
X759117Y922366D01*
X760783D01*
G01X756850Y919866D02*
X756558Y919908D01*
X756225Y920033D01*
X756017Y920241D01*
X755933Y920533D01*
X756017Y920824D01*
X756267Y921074D01*
X756642Y921199D01*
X757058D01*
X757308Y921283D01*
X757517Y921491D01*
X757600Y921783D01*
X757475Y922074D01*
X757183Y922283D01*
X756850Y922366D01*
X756517Y922283D01*
X756225Y922074D01*
X756100Y921783D01*
X756183Y921491D01*
X756392Y921283D01*
X756642Y921199D01*
X757058D01*
X757433Y921074D01*
X757683Y920824D01*
X757767Y920533D01*
X757683Y920241D01*
X757475Y920033D01*
X757142Y919908D01*
X756850Y919866D01*
G01X772892Y892267D02*
X773017Y892017D01*
X773100Y891725D01*
Y891392D01*
X772975Y891017D01*
X772767Y890725D01*
X772517Y890517D01*
X772100Y890350D01*
X771725Y890308D01*
X771350Y890392D01*
X771100Y890517D01*
X770850Y890767D01*
X770683Y891058D01*
X770600Y891350D01*
Y891642D01*
X770683Y891933D01*
X770808Y892183D01*
X770975Y892392D01*
G01X771642Y893658D02*
X771933Y893950D01*
X772100Y894200D01*
X772183Y894533D01*
X772100Y894825D01*
X771933Y895033D01*
X771683Y895200D01*
X771392Y895242D01*
X771142Y895200D01*
X770892Y895033D01*
X770683Y894783D01*
X770600Y894492D01*
X770683Y894158D01*
X770933Y893867D01*
X771308Y893700D01*
X771725Y893658D01*
X772267Y893742D01*
X772558Y893867D01*
X772850Y894075D01*
X773058Y894367D01*
X773100Y894658D01*
X773017Y894950D01*
X772808Y895158D01*
G01X770600Y897467D02*
X771142Y897550D01*
X771600Y897675D01*
X772017Y897842D01*
X772475Y898050D01*
X773100Y898383D01*
Y896717D01*
G01Y900650D02*
X773017Y900317D01*
X772808Y900067D01*
X772558Y899900D01*
X772225Y899775D01*
X771850Y899733D01*
X771475Y899775D01*
X771142Y899900D01*
X770892Y900067D01*
X770683Y900317D01*
X770600Y900650D01*
X770683Y900983D01*
X770892Y901233D01*
X771142Y901400D01*
X771475Y901525D01*
X771850Y901567D01*
X772225Y901525D01*
X772558Y901400D01*
X772808Y901233D01*
X773017Y900983D01*
X773100Y900650D01*
G01X765815Y947794D02*
X766065Y947919D01*
X766357Y948002D01*
X766690D01*
X767065Y947877D01*
X767357Y947669D01*
X767565Y947419D01*
X767732Y947002D01*
X767774Y946627D01*
X767690Y946252D01*
X767565Y946002D01*
X767315Y945752D01*
X767024Y945585D01*
X766732Y945502D01*
X766440D01*
X766149Y945585D01*
X765899Y945710D01*
X765690Y945877D01*
G01X764424Y946544D02*
X764132Y946835D01*
X763882Y947002D01*
X763549Y947085D01*
X763257Y947002D01*
X763049Y946835D01*
X762882Y946585D01*
X762840Y946294D01*
X762882Y946044D01*
X763049Y945794D01*
X763299Y945585D01*
X763590Y945502D01*
X763924Y945585D01*
X764215Y945835D01*
X764382Y946210D01*
X764424Y946627D01*
X764340Y947169D01*
X764215Y947460D01*
X764007Y947752D01*
X763715Y947960D01*
X763424Y948002D01*
X763132Y947919D01*
X762924Y947710D01*
G01X760532Y945502D02*
X760240Y945544D01*
X759907Y945669D01*
X759699Y945877D01*
X759615Y946169D01*
X759699Y946460D01*
X759949Y946710D01*
X760324Y946835D01*
X760740D01*
X760990Y946919D01*
X761199Y947127D01*
X761282Y947419D01*
X761157Y947710D01*
X760865Y947919D01*
X760532Y948002D01*
X760199Y947919D01*
X759907Y947710D01*
X759782Y947419D01*
X759865Y947127D01*
X760074Y946919D01*
X760324Y946835D01*
X760740D01*
X761115Y946710D01*
X761365Y946460D01*
X761449Y946169D01*
X761365Y945877D01*
X761157Y945669D01*
X760824Y945544D01*
X760532Y945502D01*
G01X757432D02*
Y948002D01*
X757932Y947502D01*
G01Y945502D02*
X756932D01*
G01X846233Y408459D02*
X846483Y408584D01*
X846775Y408667D01*
X847108D01*
X847483Y408542D01*
X847775Y408334D01*
X847983Y408084D01*
X848150Y407667D01*
X848192Y407292D01*
X848108Y406917D01*
X847983Y406667D01*
X847733Y406417D01*
X847442Y406250D01*
X847150Y406167D01*
X846858D01*
X846567Y406250D01*
X846317Y406375D01*
X846108Y406542D01*
G01X844967D02*
X844717Y406334D01*
X844425Y406209D01*
X844050Y406167D01*
X843675Y406250D01*
X843383Y406417D01*
X843175Y406709D01*
X843133Y407042D01*
X843217Y407375D01*
X843425Y407584D01*
X843717Y407750D01*
X844008Y407792D01*
X844300Y407750D01*
X844675Y407584D01*
X844550Y408667D01*
X843425D01*
G01X841742Y408250D02*
X841492Y408500D01*
X841200Y408625D01*
X840867Y408667D01*
X840450Y408584D01*
X840158Y408375D01*
X840075Y408125D01*
X840117Y407875D01*
X840283Y407667D01*
X841117Y407250D01*
X841492Y406959D01*
X841742Y406542D01*
X841825Y406167D01*
X840075D01*
G01X838558Y406459D02*
X838267Y406250D01*
X837933Y406167D01*
X837600Y406250D01*
X837308Y406500D01*
X837100Y406875D01*
X837017Y407250D01*
Y407709D01*
X837100Y408084D01*
X837308Y408417D01*
X837558Y408584D01*
X837850Y408667D01*
X838183Y408584D01*
X838433Y408417D01*
X838600Y408167D01*
X838683Y407834D01*
X838600Y407542D01*
X838392Y407250D01*
X838142Y407084D01*
X837850Y407042D01*
X837517Y407125D01*
X837267Y407334D01*
X837017Y407709D01*
G01X846683Y397459D02*
X846933Y397584D01*
X847225Y397667D01*
X847558D01*
X847933Y397542D01*
X848225Y397334D01*
X848433Y397084D01*
X848600Y396667D01*
X848642Y396292D01*
X848558Y395917D01*
X848433Y395667D01*
X848183Y395417D01*
X847892Y395250D01*
X847600Y395167D01*
X847308D01*
X847017Y395250D01*
X846767Y395375D01*
X846558Y395542D01*
G01X845417Y395667D02*
X845167Y395375D01*
X844833Y395209D01*
X844458Y395167D01*
X844125Y395209D01*
X843792Y395417D01*
X843583Y395667D01*
X843542Y395917D01*
X843625Y396209D01*
X843917Y396417D01*
X844208Y396500D01*
X844583D01*
G01X844208D02*
X843958Y396625D01*
X843750Y396834D01*
X843667Y397084D01*
X843750Y397334D01*
X843958Y397542D01*
X844333Y397667D01*
X844708Y397625D01*
X845083Y397459D01*
G01X841400Y395167D02*
Y397667D01*
X841900Y397167D01*
G01Y395167D02*
X840900D01*
G01X842641Y424026D02*
Y421526D01*
G01X843599Y424026D02*
X841683D01*
G01X838624Y423818D02*
X838874Y423943D01*
X839166Y424026D01*
X839499D01*
X839874Y423901D01*
X840166Y423693D01*
X840374Y423443D01*
X840541Y423026D01*
X840583Y422651D01*
X840499Y422276D01*
X840374Y422026D01*
X840124Y421776D01*
X839833Y421609D01*
X839541Y421526D01*
X839249D01*
X838958Y421609D01*
X838708Y421734D01*
X838499Y421901D01*
G01X837358Y422026D02*
X837108Y421734D01*
X836774Y421568D01*
X836399Y421526D01*
X836066Y421568D01*
X835733Y421776D01*
X835524Y422026D01*
X835483Y422276D01*
X835566Y422568D01*
X835858Y422776D01*
X836149Y422859D01*
X836524D01*
G01X836149D02*
X835899Y422984D01*
X835691Y423193D01*
X835608Y423443D01*
X835691Y423693D01*
X835899Y423901D01*
X836274Y424026D01*
X836649Y423984D01*
X837024Y423818D01*
G01X847857Y456676D02*
Y459176D01*
X846816D01*
X846482Y459051D01*
X846274Y458884D01*
X846191Y458551D01*
X846274Y458218D01*
X846524Y458009D01*
X846816Y457884D01*
X847857D01*
G01X846816D02*
X846191Y456676D01*
G01X844716Y457718D02*
X844424Y458009D01*
X844174Y458176D01*
X843841Y458259D01*
X843549Y458176D01*
X843341Y458009D01*
X843174Y457759D01*
X843132Y457468D01*
X843174Y457218D01*
X843341Y456968D01*
X843591Y456759D01*
X843882Y456676D01*
X844216Y456759D01*
X844507Y457009D01*
X844674Y457384D01*
X844716Y457801D01*
X844632Y458343D01*
X844507Y458634D01*
X844299Y458926D01*
X844007Y459134D01*
X843716Y459176D01*
X843424Y459093D01*
X843216Y458884D01*
G01X841616Y458759D02*
X841366Y459009D01*
X841074Y459134D01*
X840741Y459176D01*
X840324Y459093D01*
X840032Y458884D01*
X839949Y458634D01*
X839991Y458384D01*
X840157Y458176D01*
X840991Y457759D01*
X841366Y457468D01*
X841616Y457051D01*
X841699Y456676D01*
X839949D01*
G01X838516Y458759D02*
X838266Y459009D01*
X837974Y459134D01*
X837641Y459176D01*
X837224Y459093D01*
X836932Y458884D01*
X836849Y458634D01*
X836891Y458384D01*
X837057Y458176D01*
X837891Y457759D01*
X838266Y457468D01*
X838516Y457051D01*
X838599Y456676D01*
X836849D01*
G01X841892Y470467D02*
X842017Y470217D01*
X842100Y469925D01*
Y469592D01*
X841975Y469217D01*
X841767Y468925D01*
X841517Y468717D01*
X841100Y468550D01*
X840725Y468508D01*
X840350Y468592D01*
X840100Y468717D01*
X839850Y468967D01*
X839683Y469258D01*
X839600Y469550D01*
Y469842D01*
X839683Y470133D01*
X839808Y470383D01*
X839975Y470592D01*
G01X841683Y471858D02*
X841933Y472108D01*
X842058Y472400D01*
X842100Y472733D01*
X842017Y473150D01*
X841808Y473442D01*
X841558Y473525D01*
X841308Y473483D01*
X841100Y473317D01*
X840683Y472483D01*
X840392Y472108D01*
X839975Y471858D01*
X839600Y471775D01*
Y473525D01*
G01X844117Y479800D02*
Y478008D01*
X843950Y477633D01*
X843617Y477383D01*
X843200Y477300D01*
X842783Y477383D01*
X842450Y477633D01*
X842283Y478008D01*
Y479800D01*
G01X839600Y477300D02*
Y479800D01*
X841142Y478008D01*
X839058D01*
G01X837708Y477592D02*
X837417Y477383D01*
X837083Y477300D01*
X836750Y477383D01*
X836458Y477633D01*
X836250Y478008D01*
X836167Y478383D01*
Y478842D01*
X836250Y479217D01*
X836458Y479550D01*
X836708Y479717D01*
X837000Y479800D01*
X837333Y479717D01*
X837583Y479550D01*
X837750Y479300D01*
X837833Y478967D01*
X837750Y478675D01*
X837542Y478383D01*
X837292Y478217D01*
X837000Y478175D01*
X836667Y478258D01*
X836417Y478467D01*
X836167Y478842D01*
G01X857532Y401400D02*
X876232D01*
Y411700D01*
X857532D01*
Y401400D01*
G01X863543Y448084D02*
Y450584D01*
X862502D01*
X862168Y450459D01*
X861960Y450292D01*
X861877Y449959D01*
X861960Y449626D01*
X862210Y449417D01*
X862502Y449292D01*
X863543D01*
G01X862502D02*
X861877Y448084D01*
G01X860402Y449126D02*
X860110Y449417D01*
X859860Y449584D01*
X859527Y449667D01*
X859235Y449584D01*
X859027Y449417D01*
X858860Y449167D01*
X858818Y448876D01*
X858860Y448626D01*
X859027Y448376D01*
X859277Y448167D01*
X859568Y448084D01*
X859902Y448167D01*
X860193Y448417D01*
X860360Y448792D01*
X860402Y449209D01*
X860318Y449751D01*
X860193Y450042D01*
X859985Y450334D01*
X859693Y450542D01*
X859402Y450584D01*
X859110Y450501D01*
X858902Y450292D01*
G01X856510Y448084D02*
Y450584D01*
X857010Y450084D01*
G01Y448084D02*
X856010D01*
G01X854118Y448376D02*
X853827Y448167D01*
X853493Y448084D01*
X853160Y448167D01*
X852868Y448417D01*
X852660Y448792D01*
X852577Y449167D01*
Y449626D01*
X852660Y450001D01*
X852868Y450334D01*
X853118Y450501D01*
X853410Y450584D01*
X853743Y450501D01*
X853993Y450334D01*
X854160Y450084D01*
X854243Y449751D01*
X854160Y449459D01*
X853952Y449167D01*
X853702Y449001D01*
X853410Y448959D01*
X853077Y449042D01*
X852827Y449251D01*
X852577Y449626D01*
G01X874500Y448917D02*
X877000D01*
Y449958D01*
X876875Y450292D01*
X876708Y450500D01*
X876375Y450583D01*
X876042Y450500D01*
X875833Y450250D01*
X875708Y449958D01*
Y448917D01*
G01Y449958D02*
X874500Y450583D01*
G01Y452850D02*
X877000D01*
X876500Y452350D01*
G01X874500D02*
Y453350D01*
G01Y455950D02*
X874542Y456242D01*
X874667Y456575D01*
X874875Y456783D01*
X875167Y456867D01*
X875458Y456783D01*
X875708Y456533D01*
X875833Y456158D01*
Y455742D01*
X875917Y455492D01*
X876125Y455283D01*
X876417Y455200D01*
X876708Y455325D01*
X876917Y455617D01*
X877000Y455950D01*
X876917Y456283D01*
X876708Y456575D01*
X876417Y456700D01*
X876125Y456617D01*
X875917Y456408D01*
X875833Y456158D01*
Y455742D01*
X875708Y455367D01*
X875458Y455117D01*
X875167Y455033D01*
X874875Y455117D01*
X874667Y455325D01*
X874542Y455658D01*
X874500Y455950D01*
G01Y459050D02*
X874542Y459342D01*
X874667Y459675D01*
X874875Y459883D01*
X875167Y459967D01*
X875458Y459883D01*
X875708Y459633D01*
X875833Y459258D01*
Y458842D01*
X875917Y458592D01*
X876125Y458383D01*
X876417Y458300D01*
X876708Y458425D01*
X876917Y458717D01*
X877000Y459050D01*
X876917Y459383D01*
X876708Y459675D01*
X876417Y459800D01*
X876125Y459717D01*
X875917Y459508D01*
X875833Y459258D01*
Y458842D01*
X875708Y458467D01*
X875458Y458217D01*
X875167Y458133D01*
X874875Y458217D01*
X874667Y458425D01*
X874542Y458758D01*
X874500Y459050D01*
G01X886449Y414076D02*
X875249D01*
G01X886449Y432076D02*
Y414076D01*
G01X875249Y432076D02*
X886449D01*
G01X848049Y414076D02*
X859249D01*
G01X848049Y432076D02*
Y414076D01*
G01X859249Y432076D02*
X848049D01*
G01X876592Y441967D02*
X876717Y441717D01*
X876800Y441425D01*
Y441092D01*
X876675Y440717D01*
X876467Y440425D01*
X876217Y440217D01*
X875800Y440050D01*
X875425Y440008D01*
X875050Y440092D01*
X874800Y440217D01*
X874550Y440467D01*
X874383Y440758D01*
X874300Y441050D01*
Y441342D01*
X874383Y441633D01*
X874508Y441883D01*
X874675Y442092D01*
G01X874800Y443233D02*
X874508Y443483D01*
X874342Y443817D01*
X874300Y444192D01*
X874342Y444525D01*
X874550Y444858D01*
X874800Y445067D01*
X875050Y445108D01*
X875342Y445025D01*
X875550Y444733D01*
X875633Y444442D01*
Y444067D01*
G01Y444442D02*
X875758Y444692D01*
X875967Y444900D01*
X876217Y444983D01*
X876467Y444900D01*
X876675Y444692D01*
X876800Y444317D01*
X876758Y443942D01*
X876592Y443567D01*
G01X865000Y460600D02*
Y456600D01*
X857600D01*
G01X850000Y456500D02*
Y460500D01*
X857400D01*
G01X850076Y496243D02*
X852576D01*
Y497284D01*
X852451Y497618D01*
X852284Y497826D01*
X851951Y497909D01*
X851618Y497826D01*
X851409Y497576D01*
X851284Y497284D01*
Y496243D01*
G01Y497284D02*
X850076Y497909D01*
G01X850576Y499259D02*
X850284Y499509D01*
X850118Y499843D01*
X850076Y500218D01*
X850118Y500551D01*
X850326Y500884D01*
X850576Y501093D01*
X850826Y501134D01*
X851118Y501051D01*
X851326Y500759D01*
X851409Y500468D01*
Y500093D01*
G01Y500468D02*
X851534Y500718D01*
X851743Y500926D01*
X851993Y501009D01*
X852243Y500926D01*
X852451Y500718D01*
X852576Y500343D01*
X852534Y499968D01*
X852368Y499593D01*
G01X850451Y502359D02*
X850243Y502609D01*
X850118Y502901D01*
X850076Y503276D01*
X850159Y503651D01*
X850326Y503943D01*
X850618Y504151D01*
X850951Y504193D01*
X851284Y504109D01*
X851493Y503901D01*
X851659Y503609D01*
X851701Y503318D01*
X851659Y503026D01*
X851493Y502651D01*
X852576Y502776D01*
Y503901D01*
G01X850451Y505459D02*
X850243Y505709D01*
X850118Y506001D01*
X850076Y506376D01*
X850159Y506751D01*
X850326Y507043D01*
X850618Y507251D01*
X850951Y507293D01*
X851284Y507209D01*
X851493Y507001D01*
X851659Y506709D01*
X851701Y506418D01*
X851659Y506126D01*
X851493Y505751D01*
X852576Y505876D01*
Y507001D01*
G01X854500Y482500D02*
X850500D01*
Y489900D01*
G01X860884Y496157D02*
X863384D01*
Y497198D01*
X863259Y497532D01*
X863092Y497740D01*
X862759Y497823D01*
X862426Y497740D01*
X862217Y497490D01*
X862092Y497198D01*
Y496157D01*
G01Y497198D02*
X860884Y497823D01*
G01X861384Y499173D02*
X861092Y499423D01*
X860926Y499757D01*
X860884Y500132D01*
X860926Y500465D01*
X861134Y500798D01*
X861384Y501007D01*
X861634Y501048D01*
X861926Y500965D01*
X862134Y500673D01*
X862217Y500382D01*
Y500007D01*
G01Y500382D02*
X862342Y500632D01*
X862551Y500840D01*
X862801Y500923D01*
X863051Y500840D01*
X863259Y500632D01*
X863384Y500257D01*
X863342Y499882D01*
X863176Y499507D01*
G01X860884Y503690D02*
X863384D01*
X861592Y502148D01*
Y504232D01*
G01X861176Y505582D02*
X860967Y505873D01*
X860884Y506207D01*
X860967Y506540D01*
X861217Y506832D01*
X861592Y507040D01*
X861967Y507123D01*
X862426D01*
X862801Y507040D01*
X863134Y506832D01*
X863301Y506582D01*
X863384Y506290D01*
X863301Y505957D01*
X863134Y505707D01*
X862884Y505540D01*
X862551Y505457D01*
X862259Y505540D01*
X861967Y505748D01*
X861801Y505998D01*
X861759Y506290D01*
X861842Y506623D01*
X862051Y506873D01*
X862426Y507123D01*
G01X863900Y482400D02*
X859900D01*
Y489800D01*
G01X872900Y477000D02*
X876900D01*
Y469600D01*
G01X871000Y496317D02*
X873500D01*
Y497358D01*
X873375Y497692D01*
X873208Y497900D01*
X872875Y497983D01*
X872542Y497900D01*
X872333Y497650D01*
X872208Y497358D01*
Y496317D01*
G01Y497358D02*
X871000Y497983D01*
G01X871500Y499333D02*
X871208Y499583D01*
X871042Y499917D01*
X871000Y500292D01*
X871042Y500625D01*
X871250Y500958D01*
X871500Y501167D01*
X871750Y501208D01*
X872042Y501125D01*
X872250Y500833D01*
X872333Y500542D01*
Y500167D01*
G01Y500542D02*
X872458Y500792D01*
X872667Y501000D01*
X872917Y501083D01*
X873167Y501000D01*
X873375Y500792D01*
X873500Y500417D01*
X873458Y500042D01*
X873292Y499667D01*
G01X872042Y502558D02*
X872333Y502850D01*
X872500Y503100D01*
X872583Y503433D01*
X872500Y503725D01*
X872333Y503933D01*
X872083Y504100D01*
X871792Y504142D01*
X871542Y504100D01*
X871292Y503933D01*
X871083Y503683D01*
X871000Y503392D01*
X871083Y503058D01*
X871333Y502767D01*
X871708Y502600D01*
X872125Y502558D01*
X872667Y502642D01*
X872958Y502767D01*
X873250Y502975D01*
X873458Y503267D01*
X873500Y503558D01*
X873417Y503850D01*
X873208Y504058D01*
G01X871292Y505742D02*
X871083Y506033D01*
X871000Y506367D01*
X871083Y506700D01*
X871333Y506992D01*
X871708Y507200D01*
X872083Y507283D01*
X872542D01*
X872917Y507200D01*
X873250Y506992D01*
X873417Y506742D01*
X873500Y506450D01*
X873417Y506117D01*
X873250Y505867D01*
X873000Y505700D01*
X872667Y505617D01*
X872375Y505700D01*
X872083Y505908D01*
X871917Y506158D01*
X871875Y506450D01*
X871958Y506783D01*
X872167Y507033D01*
X872542Y507283D01*
G01X870000Y489700D02*
X874000D01*
Y482300D01*
G01X855224Y496469D02*
X857724D01*
Y497510D01*
X857599Y497844D01*
X857432Y498052D01*
X857099Y498135D01*
X856766Y498052D01*
X856557Y497802D01*
X856432Y497510D01*
Y496469D01*
G01Y497510D02*
X855224Y498135D01*
G01X856266Y499610D02*
X856557Y499902D01*
X856724Y500152D01*
X856807Y500485D01*
X856724Y500777D01*
X856557Y500985D01*
X856307Y501152D01*
X856016Y501194D01*
X855766Y501152D01*
X855516Y500985D01*
X855307Y500735D01*
X855224Y500444D01*
X855307Y500110D01*
X855557Y499819D01*
X855932Y499652D01*
X856349Y499610D01*
X856891Y499694D01*
X857182Y499819D01*
X857474Y500027D01*
X857682Y500319D01*
X857724Y500610D01*
X857641Y500902D01*
X857432Y501110D01*
G01X855724Y502585D02*
X855432Y502835D01*
X855266Y503169D01*
X855224Y503544D01*
X855266Y503877D01*
X855474Y504210D01*
X855724Y504419D01*
X855974Y504460D01*
X856266Y504377D01*
X856474Y504085D01*
X856557Y503794D01*
Y503419D01*
G01Y503794D02*
X856682Y504044D01*
X856891Y504252D01*
X857141Y504335D01*
X857391Y504252D01*
X857599Y504044D01*
X857724Y503669D01*
X857682Y503294D01*
X857516Y502919D01*
G01X855516Y505894D02*
X855307Y506185D01*
X855224Y506519D01*
X855307Y506852D01*
X855557Y507144D01*
X855932Y507352D01*
X856307Y507435D01*
X856766D01*
X857141Y507352D01*
X857474Y507144D01*
X857641Y506894D01*
X857724Y506602D01*
X857641Y506269D01*
X857474Y506019D01*
X857224Y505852D01*
X856891Y505769D01*
X856599Y505852D01*
X856307Y506060D01*
X856141Y506310D01*
X856099Y506602D01*
X856182Y506935D01*
X856391Y507185D01*
X856766Y507435D01*
G01X854900Y489900D02*
X858900D01*
Y482500D01*
G01X865124Y496169D02*
X867624D01*
Y497210D01*
X867499Y497544D01*
X867332Y497752D01*
X866999Y497835D01*
X866666Y497752D01*
X866457Y497502D01*
X866332Y497210D01*
Y496169D01*
G01Y497210D02*
X865124Y497835D01*
G01Y500602D02*
X867624D01*
X865832Y499060D01*
Y501144D01*
G01X865499Y502285D02*
X865291Y502535D01*
X865166Y502827D01*
X865124Y503202D01*
X865207Y503577D01*
X865374Y503869D01*
X865666Y504077D01*
X865999Y504119D01*
X866332Y504035D01*
X866541Y503827D01*
X866707Y503535D01*
X866749Y503244D01*
X866707Y502952D01*
X866541Y502577D01*
X867624Y502702D01*
Y503827D01*
G01Y506302D02*
X867541Y505969D01*
X867332Y505719D01*
X867082Y505552D01*
X866749Y505427D01*
X866374Y505385D01*
X865999Y505427D01*
X865666Y505552D01*
X865416Y505719D01*
X865207Y505969D01*
X865124Y506302D01*
X865207Y506635D01*
X865416Y506885D01*
X865666Y507052D01*
X865999Y507177D01*
X866374Y507219D01*
X866749Y507177D01*
X867082Y507052D01*
X867332Y506885D01*
X867541Y506635D01*
X867624Y506302D01*
G01X864100Y489800D02*
X868100D01*
Y482400D01*
G01X862900Y466550D02*
Y466700D01*
X861650Y467950D01*
X860450Y466750D01*
Y466500D01*
G01X852900Y466550D02*
X870100D01*
Y476450D01*
X852900D01*
Y466550D01*
G01X997033Y1514667D02*
Y1517167D01*
X995992D01*
X995658Y1517042D01*
X995450Y1516875D01*
X995367Y1516542D01*
X995450Y1516209D01*
X995700Y1516000D01*
X995992Y1515875D01*
X997033D01*
G01X995992D02*
X995367Y1514667D01*
G01X993100D02*
Y1517167D01*
X993600Y1516667D01*
G01Y1514667D02*
X992600D01*
G01X990000D02*
Y1517167D01*
X990500Y1516667D01*
G01Y1514667D02*
X989500D01*
G01X987817Y1515042D02*
X987567Y1514834D01*
X987275Y1514709D01*
X986900Y1514667D01*
X986525Y1514750D01*
X986233Y1514917D01*
X986025Y1515209D01*
X985983Y1515542D01*
X986067Y1515875D01*
X986275Y1516084D01*
X986567Y1516250D01*
X986858Y1516292D01*
X987150Y1516250D01*
X987525Y1516084D01*
X987400Y1517167D01*
X986275D01*
G01X983300Y1514667D02*
Y1517167D01*
X984842Y1515375D01*
X982758D01*
G01X973200Y1518700D02*
Y1514700D01*
X965800D01*
G01X961459Y1503267D02*
X961584Y1503017D01*
X961667Y1502725D01*
Y1502392D01*
X961542Y1502017D01*
X961334Y1501725D01*
X961084Y1501517D01*
X960667Y1501350D01*
X960292Y1501308D01*
X959917Y1501392D01*
X959667Y1501517D01*
X959417Y1501767D01*
X959250Y1502058D01*
X959167Y1502350D01*
Y1502642D01*
X959250Y1502933D01*
X959375Y1503183D01*
X959542Y1503392D01*
G01Y1504533D02*
X959334Y1504783D01*
X959209Y1505075D01*
X959167Y1505450D01*
X959250Y1505825D01*
X959417Y1506117D01*
X959709Y1506325D01*
X960042Y1506367D01*
X960375Y1506283D01*
X960584Y1506075D01*
X960750Y1505783D01*
X960792Y1505492D01*
X960750Y1505200D01*
X960584Y1504825D01*
X961667Y1504950D01*
Y1506075D01*
G01X959167Y1508550D02*
X959209Y1508842D01*
X959334Y1509175D01*
X959542Y1509383D01*
X959834Y1509467D01*
X960125Y1509383D01*
X960375Y1509133D01*
X960500Y1508758D01*
Y1508342D01*
X960584Y1508092D01*
X960792Y1507883D01*
X961084Y1507800D01*
X961375Y1507925D01*
X961584Y1508217D01*
X961667Y1508550D01*
X961584Y1508883D01*
X961375Y1509175D01*
X961084Y1509300D01*
X960792Y1509217D01*
X960584Y1509008D01*
X960500Y1508758D01*
Y1508342D01*
X960375Y1507967D01*
X960125Y1507717D01*
X959834Y1507633D01*
X959542Y1507717D01*
X959334Y1507925D01*
X959209Y1508258D01*
X959167Y1508550D01*
G01Y1511567D02*
X959709Y1511650D01*
X960167Y1511775D01*
X960584Y1511942D01*
X961042Y1512150D01*
X961667Y1512483D01*
Y1510817D01*
G01X997033Y1519667D02*
Y1522167D01*
X995992D01*
X995658Y1522042D01*
X995450Y1521875D01*
X995367Y1521542D01*
X995450Y1521209D01*
X995700Y1521000D01*
X995992Y1520875D01*
X997033D01*
G01X995992D02*
X995367Y1519667D01*
G01X993100D02*
Y1522167D01*
X993600Y1521667D01*
G01Y1519667D02*
X992600D01*
G01X990000D02*
Y1522167D01*
X990500Y1521667D01*
G01Y1519667D02*
X989500D01*
G01X987817Y1520042D02*
X987567Y1519834D01*
X987275Y1519709D01*
X986900Y1519667D01*
X986525Y1519750D01*
X986233Y1519917D01*
X986025Y1520209D01*
X985983Y1520542D01*
X986067Y1520875D01*
X986275Y1521084D01*
X986567Y1521250D01*
X986858Y1521292D01*
X987150Y1521250D01*
X987525Y1521084D01*
X987400Y1522167D01*
X986275D01*
G01X984592Y1520709D02*
X984300Y1521000D01*
X984050Y1521167D01*
X983717Y1521250D01*
X983425Y1521167D01*
X983217Y1521000D01*
X983050Y1520750D01*
X983008Y1520459D01*
X983050Y1520209D01*
X983217Y1519959D01*
X983467Y1519750D01*
X983758Y1519667D01*
X984092Y1519750D01*
X984383Y1520000D01*
X984550Y1520375D01*
X984592Y1520792D01*
X984508Y1521334D01*
X984383Y1521625D01*
X984175Y1521917D01*
X983883Y1522125D01*
X983592Y1522167D01*
X983300Y1522084D01*
X983092Y1521875D01*
G01X973200Y1522700D02*
Y1518700D01*
X965800D01*
G01X1036233Y404959D02*
X1036483Y405084D01*
X1036775Y405167D01*
X1037108D01*
X1037483Y405042D01*
X1037775Y404834D01*
X1037983Y404584D01*
X1038150Y404167D01*
X1038192Y403792D01*
X1038108Y403417D01*
X1037983Y403167D01*
X1037733Y402917D01*
X1037442Y402750D01*
X1037150Y402667D01*
X1036858D01*
X1036567Y402750D01*
X1036317Y402875D01*
X1036108Y403042D01*
G01X1034967D02*
X1034717Y402834D01*
X1034425Y402709D01*
X1034050Y402667D01*
X1033675Y402750D01*
X1033383Y402917D01*
X1033175Y403209D01*
X1033133Y403542D01*
X1033217Y403875D01*
X1033425Y404084D01*
X1033717Y404250D01*
X1034008Y404292D01*
X1034300Y404250D01*
X1034675Y404084D01*
X1034550Y405167D01*
X1033425D01*
G01X1031742Y404750D02*
X1031492Y405000D01*
X1031200Y405125D01*
X1030867Y405167D01*
X1030450Y405084D01*
X1030158Y404875D01*
X1030075Y404625D01*
X1030117Y404375D01*
X1030283Y404167D01*
X1031117Y403750D01*
X1031492Y403459D01*
X1031742Y403042D01*
X1031825Y402667D01*
X1030075D01*
G01X1027850Y405167D02*
X1028183Y405084D01*
X1028433Y404875D01*
X1028600Y404625D01*
X1028725Y404292D01*
X1028767Y403917D01*
X1028725Y403542D01*
X1028600Y403209D01*
X1028433Y402959D01*
X1028183Y402750D01*
X1027850Y402667D01*
X1027517Y402750D01*
X1027267Y402959D01*
X1027100Y403209D01*
X1026975Y403542D01*
X1026933Y403917D01*
X1026975Y404292D01*
X1027100Y404625D01*
X1027267Y404875D01*
X1027517Y405084D01*
X1027850Y405167D01*
G01X1040357Y397459D02*
X1040607Y397584D01*
X1040899Y397667D01*
X1041232D01*
X1041607Y397542D01*
X1041899Y397334D01*
X1042107Y397084D01*
X1042274Y396667D01*
X1042316Y396292D01*
X1042232Y395917D01*
X1042107Y395667D01*
X1041857Y395417D01*
X1041566Y395250D01*
X1041274Y395167D01*
X1040982D01*
X1040691Y395250D01*
X1040441Y395375D01*
X1040232Y395542D01*
G01X1039091Y395667D02*
X1038841Y395375D01*
X1038507Y395209D01*
X1038132Y395167D01*
X1037799Y395209D01*
X1037466Y395417D01*
X1037257Y395667D01*
X1037216Y395917D01*
X1037299Y396209D01*
X1037591Y396417D01*
X1037882Y396500D01*
X1038257D01*
G01X1037882D02*
X1037632Y396625D01*
X1037424Y396834D01*
X1037341Y397084D01*
X1037424Y397334D01*
X1037632Y397542D01*
X1038007Y397667D01*
X1038382Y397625D01*
X1038757Y397459D01*
G01X1035782Y395459D02*
X1035491Y395250D01*
X1035157Y395167D01*
X1034824Y395250D01*
X1034532Y395500D01*
X1034324Y395875D01*
X1034241Y396250D01*
Y396709D01*
X1034324Y397084D01*
X1034532Y397417D01*
X1034782Y397584D01*
X1035074Y397667D01*
X1035407Y397584D01*
X1035657Y397417D01*
X1035824Y397167D01*
X1035907Y396834D01*
X1035824Y396542D01*
X1035616Y396250D01*
X1035366Y396084D01*
X1035074Y396042D01*
X1034741Y396125D01*
X1034491Y396334D01*
X1034241Y396709D01*
G01X1028650Y422667D02*
Y420167D01*
G01X1029608Y422667D02*
X1027692D01*
G01X1024633Y422459D02*
X1024883Y422584D01*
X1025175Y422667D01*
X1025508D01*
X1025883Y422542D01*
X1026175Y422334D01*
X1026383Y422084D01*
X1026550Y421667D01*
X1026592Y421292D01*
X1026508Y420917D01*
X1026383Y420667D01*
X1026133Y420417D01*
X1025842Y420250D01*
X1025550Y420167D01*
X1025258D01*
X1024967Y420250D01*
X1024717Y420375D01*
X1024508Y420542D01*
G01X1023242Y422250D02*
X1022992Y422500D01*
X1022700Y422625D01*
X1022367Y422667D01*
X1021950Y422584D01*
X1021658Y422375D01*
X1021575Y422125D01*
X1021617Y421875D01*
X1021783Y421667D01*
X1022617Y421250D01*
X1022992Y420959D01*
X1023242Y420542D01*
X1023325Y420167D01*
X1021575D01*
G01X1019350D02*
Y422667D01*
X1019850Y422167D01*
G01Y420167D02*
X1018850D01*
G01X1034580Y412129D02*
X1045780D01*
G01X1034580Y430129D02*
Y412129D01*
G01X1045780Y430129D02*
X1034580D01*
G01X1051950Y399550D02*
X1070650D01*
Y409850D01*
X1051950D01*
Y399550D01*
G01X1072980Y412129D02*
X1061780D01*
G01X1072980Y430129D02*
Y412129D01*
G01X1061780Y430129D02*
X1072980D01*
G01X1367988Y99781D02*
Y100781D01*
G01Y100281D02*
X1365488D01*
G01Y99781D02*
Y100781D01*
G01Y103381D02*
X1365530Y103048D01*
X1365696Y102756D01*
X1365946Y102506D01*
X1366238Y102339D01*
X1366571Y102256D01*
X1366905D01*
X1367238Y102339D01*
X1367530Y102506D01*
X1367780Y102756D01*
X1367946Y103048D01*
X1367988Y103381D01*
X1367946Y103714D01*
X1367780Y104006D01*
X1367530Y104256D01*
X1367238Y104423D01*
X1366905Y104506D01*
X1366571D01*
X1366238Y104423D01*
X1365946Y104256D01*
X1365696Y104006D01*
X1365530Y103714D01*
X1365488Y103381D01*
G01X1367571Y105689D02*
X1367821Y105939D01*
X1367946Y106231D01*
X1367988Y106564D01*
X1367905Y106981D01*
X1367696Y107273D01*
X1367446Y107356D01*
X1367196Y107314D01*
X1366988Y107148D01*
X1366571Y106314D01*
X1366280Y105939D01*
X1365863Y105689D01*
X1365488Y105606D01*
Y107356D01*
G01X1392150Y609000D02*
Y583800D01*
X1353850D01*
Y609000D01*
X1392150D01*
G01X1377717Y611200D02*
Y613700D01*
X1376883D01*
X1376550Y613575D01*
X1376300Y613408D01*
X1376092Y613158D01*
X1375925Y612867D01*
X1375883Y612450D01*
X1375925Y612033D01*
X1376092Y611742D01*
X1376300Y611492D01*
X1376550Y611325D01*
X1376883Y611200D01*
X1377717D01*
G01X1374617Y611700D02*
X1374367Y611408D01*
X1374033Y611242D01*
X1373658Y611200D01*
X1373325Y611242D01*
X1372992Y611450D01*
X1372783Y611700D01*
X1372742Y611950D01*
X1372825Y612242D01*
X1373117Y612450D01*
X1373408Y612533D01*
X1373783D01*
G01X1373408D02*
X1373158Y612658D01*
X1372950Y612867D01*
X1372867Y613117D01*
X1372950Y613367D01*
X1373158Y613575D01*
X1373533Y613700D01*
X1373908Y613658D01*
X1374283Y613492D01*
G01X1370600Y611200D02*
X1370308Y611242D01*
X1369975Y611367D01*
X1369767Y611575D01*
X1369683Y611867D01*
X1369767Y612158D01*
X1370017Y612408D01*
X1370392Y612533D01*
X1370808D01*
X1371058Y612617D01*
X1371267Y612825D01*
X1371350Y613117D01*
X1371225Y613408D01*
X1370933Y613617D01*
X1370600Y613700D01*
X1370267Y613617D01*
X1369975Y613408D01*
X1369850Y613117D01*
X1369933Y612825D01*
X1370142Y612617D01*
X1370392Y612533D01*
X1370808D01*
X1371183Y612408D01*
X1371433Y612158D01*
X1371517Y611867D01*
X1371433Y611575D01*
X1371225Y611367D01*
X1370892Y611242D01*
X1370600Y611200D01*
G01X1367466Y664043D02*
Y666543D01*
X1365550Y664043D01*
Y666543D01*
G01X1364325D02*
Y664751D01*
X1364158Y664376D01*
X1363825Y664126D01*
X1363408Y664043D01*
X1362991Y664126D01*
X1362658Y664376D01*
X1362491Y664751D01*
Y666543D01*
G01X1360308D02*
Y664043D01*
G01X1361266Y666543D02*
X1359350D01*
G01X1358125Y664418D02*
X1357875Y664210D01*
X1357583Y664085D01*
X1357208Y664043D01*
X1356833Y664126D01*
X1356541Y664293D01*
X1356333Y664585D01*
X1356291Y664918D01*
X1356375Y665251D01*
X1356583Y665460D01*
X1356875Y665626D01*
X1357166Y665668D01*
X1357458Y665626D01*
X1357833Y665460D01*
X1357708Y666543D01*
X1356583D01*
G01X1388374Y135976D02*
Y59056D01*
X1541574D01*
Y135976D01*
X1388374D01*
G01X1433733Y566100D02*
Y568600D01*
X1432692D01*
X1432358Y568475D01*
X1432150Y568308D01*
X1432067Y567975D01*
X1432150Y567642D01*
X1432400Y567433D01*
X1432692Y567308D01*
X1433733D01*
G01X1432692D02*
X1432067Y566100D01*
G01X1429800D02*
Y568600D01*
X1430300Y568100D01*
G01Y566100D02*
X1429300D01*
G01X1426700Y568600D02*
X1427033Y568517D01*
X1427283Y568308D01*
X1427450Y568058D01*
X1427575Y567725D01*
X1427617Y567350D01*
X1427575Y566975D01*
X1427450Y566642D01*
X1427283Y566392D01*
X1427033Y566183D01*
X1426700Y566100D01*
X1426367Y566183D01*
X1426117Y566392D01*
X1425950Y566642D01*
X1425825Y566975D01*
X1425783Y567350D01*
X1425825Y567725D01*
X1425950Y568058D01*
X1426117Y568308D01*
X1426367Y568517D01*
X1426700Y568600D01*
G01X1423600Y566100D02*
X1423308Y566142D01*
X1422975Y566267D01*
X1422767Y566475D01*
X1422683Y566767D01*
X1422767Y567058D01*
X1423017Y567308D01*
X1423392Y567433D01*
X1423808D01*
X1424058Y567517D01*
X1424267Y567725D01*
X1424350Y568017D01*
X1424225Y568308D01*
X1423933Y568517D01*
X1423600Y568600D01*
X1423267Y568517D01*
X1422975Y568308D01*
X1422850Y568017D01*
X1422933Y567725D01*
X1423142Y567517D01*
X1423392Y567433D01*
X1423808D01*
X1424183Y567308D01*
X1424433Y567058D01*
X1424517Y566767D01*
X1424433Y566475D01*
X1424225Y566267D01*
X1423892Y566142D01*
X1423600Y566100D01*
G01X1420583D02*
X1420500Y566642D01*
X1420375Y567100D01*
X1420208Y567517D01*
X1420000Y567975D01*
X1419667Y568600D01*
X1421333D01*
G01X1424000Y556100D02*
Y560100D01*
X1431400D01*
G01X1433733Y570100D02*
Y572600D01*
X1432692D01*
X1432358Y572475D01*
X1432150Y572308D01*
X1432067Y571975D01*
X1432150Y571642D01*
X1432400Y571433D01*
X1432692Y571308D01*
X1433733D01*
G01X1432692D02*
X1432067Y570100D01*
G01X1429800D02*
Y572600D01*
X1430300Y572100D01*
G01Y570100D02*
X1429300D01*
G01X1426700Y572600D02*
X1427033Y572517D01*
X1427283Y572308D01*
X1427450Y572058D01*
X1427575Y571725D01*
X1427617Y571350D01*
X1427575Y570975D01*
X1427450Y570642D01*
X1427283Y570392D01*
X1427033Y570183D01*
X1426700Y570100D01*
X1426367Y570183D01*
X1426117Y570392D01*
X1425950Y570642D01*
X1425825Y570975D01*
X1425783Y571350D01*
X1425825Y571725D01*
X1425950Y572058D01*
X1426117Y572308D01*
X1426367Y572517D01*
X1426700Y572600D01*
G01X1423600Y570100D02*
X1423308Y570142D01*
X1422975Y570267D01*
X1422767Y570475D01*
X1422683Y570767D01*
X1422767Y571058D01*
X1423017Y571308D01*
X1423392Y571433D01*
X1423808D01*
X1424058Y571517D01*
X1424267Y571725D01*
X1424350Y572017D01*
X1424225Y572308D01*
X1423933Y572517D01*
X1423600Y572600D01*
X1423267Y572517D01*
X1422975Y572308D01*
X1422850Y572017D01*
X1422933Y571725D01*
X1423142Y571517D01*
X1423392Y571433D01*
X1423808D01*
X1424183Y571308D01*
X1424433Y571058D01*
X1424517Y570767D01*
X1424433Y570475D01*
X1424225Y570267D01*
X1423892Y570142D01*
X1423600Y570100D01*
G01X1421292Y571142D02*
X1421000Y571433D01*
X1420750Y571600D01*
X1420417Y571683D01*
X1420125Y571600D01*
X1419917Y571433D01*
X1419750Y571183D01*
X1419708Y570892D01*
X1419750Y570642D01*
X1419917Y570392D01*
X1420167Y570183D01*
X1420458Y570100D01*
X1420792Y570183D01*
X1421083Y570433D01*
X1421250Y570808D01*
X1421292Y571225D01*
X1421208Y571767D01*
X1421083Y572058D01*
X1420875Y572350D01*
X1420583Y572558D01*
X1420292Y572600D01*
X1420000Y572517D01*
X1419792Y572308D01*
G01X1424000Y560100D02*
Y564100D01*
X1431400D01*
G01X1457569Y50394D02*
X1458102Y50727D01*
X1458702Y50927D01*
X1459236D01*
X1459769Y50727D01*
X1460169Y50394D01*
X1460369Y49927D01*
X1460236Y49460D01*
X1459902Y49060D01*
X1459302Y48794D01*
X1458502Y48660D01*
X1458036Y48394D01*
X1457836Y47927D01*
X1457969Y47460D01*
X1458302Y47127D01*
X1458769Y46927D01*
X1459236D01*
X1459702Y47060D01*
X1460102Y47394D01*
G01X1463569Y50927D02*
Y46927D01*
G01X1468169Y48260D02*
Y50927D01*
G01Y47194D02*
X1468036Y47127D01*
Y46994D01*
X1468169Y46927D01*
X1468302Y46994D01*
Y47127D01*
X1468169Y47194D01*
G01X1472769Y46927D02*
Y50927D01*
G01X1471836Y48260D02*
X1473702D01*
G01X1445941Y134376D02*
Y130376D01*
X1447541D01*
X1448074Y130576D01*
X1448474Y131043D01*
X1448607Y131576D01*
X1448474Y132109D01*
X1448141Y132509D01*
X1447541Y132709D01*
X1445941D01*
G01X1450941Y134376D02*
Y131709D01*
G01Y132243D02*
X1451274Y131976D01*
X1451607Y131776D01*
X1452074Y131709D01*
X1452407Y131776D01*
X1452807Y131976D01*
G01X1455474Y132576D02*
X1457607D01*
X1457407Y132109D01*
X1457074Y131843D01*
X1456607Y131709D01*
X1456141Y131776D01*
X1455741Y131976D01*
X1455474Y132443D01*
X1455341Y132843D01*
Y133243D01*
X1455474Y133643D01*
X1455807Y134043D01*
X1456207Y134309D01*
X1456674Y134376D01*
X1457141Y134243D01*
X1457607Y133843D01*
G01X1460074Y133909D02*
X1460407Y134176D01*
X1460874Y134376D01*
X1461274D01*
X1461674Y134243D01*
X1461941Y134043D01*
X1462074Y133776D01*
X1462007Y133376D01*
X1461741Y133176D01*
X1460541Y132776D01*
X1460274Y132309D01*
X1460407Y131976D01*
X1460674Y131776D01*
X1461074Y131709D01*
X1461474Y131776D01*
X1461874Y131976D01*
G01X1464674Y133909D02*
X1465007Y134176D01*
X1465474Y134376D01*
X1465874D01*
X1466274Y134243D01*
X1466541Y134043D01*
X1466674Y133776D01*
X1466607Y133376D01*
X1466341Y133176D01*
X1465141Y132776D01*
X1464874Y132309D01*
X1465007Y131976D01*
X1465274Y131776D01*
X1465674Y131709D01*
X1466074Y131776D01*
X1466474Y131976D01*
G01X1473607Y134376D02*
Y130376D01*
X1476141D01*
G01X1475207Y132309D02*
X1473607D01*
G01X1479474Y131709D02*
Y134376D01*
G01Y130643D02*
X1479341Y130576D01*
Y130443D01*
X1479474Y130376D01*
X1479607Y130443D01*
Y130576D01*
X1479474Y130643D01*
G01X1484074Y130376D02*
Y134376D01*
G01X1483141Y131709D02*
X1485007D01*
G01X1438292Y566767D02*
X1438417Y566517D01*
X1438500Y566225D01*
Y565892D01*
X1438375Y565517D01*
X1438167Y565225D01*
X1437917Y565017D01*
X1437500Y564850D01*
X1437125Y564808D01*
X1436750Y564892D01*
X1436500Y565017D01*
X1436250Y565267D01*
X1436083Y565558D01*
X1436000Y565850D01*
Y566142D01*
X1436083Y566433D01*
X1436208Y566683D01*
X1436375Y566892D01*
G01Y568033D02*
X1436167Y568283D01*
X1436042Y568575D01*
X1436000Y568950D01*
X1436083Y569325D01*
X1436250Y569617D01*
X1436542Y569825D01*
X1436875Y569867D01*
X1437208Y569783D01*
X1437417Y569575D01*
X1437583Y569283D01*
X1437625Y568992D01*
X1437583Y568700D01*
X1437417Y568325D01*
X1438500Y568450D01*
Y569575D01*
G01X1436375Y571133D02*
X1436167Y571383D01*
X1436042Y571675D01*
X1436000Y572050D01*
X1436083Y572425D01*
X1436250Y572717D01*
X1436542Y572925D01*
X1436875Y572967D01*
X1437208Y572883D01*
X1437417Y572675D01*
X1437583Y572383D01*
X1437625Y572092D01*
X1437583Y571800D01*
X1437417Y571425D01*
X1438500Y571550D01*
Y572675D01*
G01X1436292Y574442D02*
X1436083Y574733D01*
X1436000Y575067D01*
X1436083Y575400D01*
X1436333Y575692D01*
X1436708Y575900D01*
X1437083Y575983D01*
X1437542D01*
X1437917Y575900D01*
X1438250Y575692D01*
X1438417Y575442D01*
X1438500Y575150D01*
X1438417Y574817D01*
X1438250Y574567D01*
X1438000Y574400D01*
X1437667Y574317D01*
X1437375Y574400D01*
X1437083Y574608D01*
X1436917Y574858D01*
X1436875Y575150D01*
X1436958Y575483D01*
X1437167Y575733D01*
X1437542Y575983D01*
G01X1461916Y888071D02*
Y890571D01*
X1460000Y888071D01*
Y890571D01*
G01X1458775D02*
Y888779D01*
X1458608Y888404D01*
X1458275Y888154D01*
X1457858Y888071D01*
X1457441Y888154D01*
X1457108Y888404D01*
X1456941Y888779D01*
Y890571D01*
G01X1454758D02*
Y888071D01*
G01X1455716Y890571D02*
X1453800D01*
G01X1451658Y888071D02*
X1451366Y888113D01*
X1451033Y888238D01*
X1450825Y888446D01*
X1450741Y888738D01*
X1450825Y889029D01*
X1451075Y889279D01*
X1451450Y889404D01*
X1451866D01*
X1452116Y889488D01*
X1452325Y889696D01*
X1452408Y889988D01*
X1452283Y890279D01*
X1451991Y890488D01*
X1451658Y890571D01*
X1451325Y890488D01*
X1451033Y890279D01*
X1450908Y889988D01*
X1450991Y889696D01*
X1451200Y889488D01*
X1451450Y889404D01*
X1451866D01*
X1452241Y889279D01*
X1452491Y889029D01*
X1452575Y888738D01*
X1452491Y888446D01*
X1452283Y888238D01*
X1451950Y888113D01*
X1451658Y888071D01*
G01X1593752Y661343D02*
Y663843D01*
X1591836Y661343D01*
Y663843D01*
G01X1590611D02*
Y662051D01*
X1590444Y661676D01*
X1590111Y661426D01*
X1589694Y661343D01*
X1589277Y661426D01*
X1588944Y661676D01*
X1588777Y662051D01*
Y663843D01*
G01X1586594D02*
Y661343D01*
G01X1587552Y663843D02*
X1585636D01*
G01X1584286Y662385D02*
X1583994Y662676D01*
X1583744Y662843D01*
X1583411Y662926D01*
X1583119Y662843D01*
X1582911Y662676D01*
X1582744Y662426D01*
X1582702Y662135D01*
X1582744Y661885D01*
X1582911Y661635D01*
X1583161Y661426D01*
X1583452Y661343D01*
X1583786Y661426D01*
X1584077Y661676D01*
X1584244Y662051D01*
X1584286Y662468D01*
X1584202Y663010D01*
X1584077Y663301D01*
X1583869Y663593D01*
X1583577Y663801D01*
X1583286Y663843D01*
X1582994Y663760D01*
X1582786Y663551D01*
G01X1678041Y768097D02*
X1677708Y767889D01*
X1677333Y767764D01*
X1676999D01*
X1676666Y767889D01*
X1676416Y768097D01*
X1676291Y768389D01*
X1676374Y768681D01*
X1676583Y768931D01*
X1676958Y769097D01*
X1677458Y769181D01*
X1677749Y769347D01*
X1677874Y769639D01*
X1677791Y769931D01*
X1677583Y770139D01*
X1677291Y770264D01*
X1676999D01*
X1676708Y770181D01*
X1676458Y769972D01*
G01X1673149Y770056D02*
X1673399Y770181D01*
X1673691Y770264D01*
X1674024D01*
X1674399Y770139D01*
X1674691Y769931D01*
X1674899Y769681D01*
X1675066Y769264D01*
X1675108Y768889D01*
X1675024Y768514D01*
X1674899Y768264D01*
X1674649Y768014D01*
X1674358Y767847D01*
X1674066Y767764D01*
X1673774D01*
X1673483Y767847D01*
X1673233Y767972D01*
X1673024Y768139D01*
G01X1672216Y770264D02*
X1671633Y767764D01*
X1670966Y770264D01*
X1670299Y767764D01*
X1669716Y770264D01*
G01X1668658Y769847D02*
X1668408Y770097D01*
X1668116Y770222D01*
X1667783Y770264D01*
X1667366Y770181D01*
X1667074Y769972D01*
X1666991Y769722D01*
X1667033Y769472D01*
X1667199Y769264D01*
X1668033Y768847D01*
X1668408Y768556D01*
X1668658Y768139D01*
X1668741Y767764D01*
X1666991D01*
G01X1699583Y985813D02*
Y999213D01*
G01X1706783Y985813D02*
X1699583D01*
G01X1706783Y999213D02*
Y985813D01*
G01X1674778Y987290D02*
X1672278D01*
Y988956D01*
G01X1672653Y990306D02*
X1672445Y990556D01*
X1672320Y990848D01*
X1672278Y991223D01*
X1672361Y991598D01*
X1672528Y991890D01*
X1672820Y992098D01*
X1673153Y992140D01*
X1673486Y992056D01*
X1673695Y991848D01*
X1673861Y991556D01*
X1673903Y991265D01*
X1673861Y990973D01*
X1673695Y990598D01*
X1674778Y990723D01*
Y991848D01*
G01X1699583Y999213D02*
X1706783D01*
G01X1678270Y989040D02*
X1678395Y988790D01*
X1678478Y988498D01*
Y988165D01*
X1678353Y987790D01*
X1678145Y987498D01*
X1677895Y987290D01*
X1677478Y987123D01*
X1677103Y987081D01*
X1676728Y987165D01*
X1676478Y987290D01*
X1676228Y987540D01*
X1676061Y987831D01*
X1675978Y988123D01*
Y988415D01*
X1676061Y988706D01*
X1676186Y988956D01*
X1676353Y989165D01*
G01X1677020Y990431D02*
X1677311Y990723D01*
X1677478Y990973D01*
X1677561Y991306D01*
X1677478Y991598D01*
X1677311Y991806D01*
X1677061Y991973D01*
X1676770Y992015D01*
X1676520Y991973D01*
X1676270Y991806D01*
X1676061Y991556D01*
X1675978Y991265D01*
X1676061Y990931D01*
X1676311Y990640D01*
X1676686Y990473D01*
X1677103Y990431D01*
X1677645Y990515D01*
X1677936Y990640D01*
X1678228Y990848D01*
X1678436Y991140D01*
X1678478Y991431D01*
X1678395Y991723D01*
X1678186Y991931D01*
G01X1676478Y993406D02*
X1676186Y993656D01*
X1676020Y993990D01*
X1675978Y994365D01*
X1676020Y994698D01*
X1676228Y995031D01*
X1676478Y995240D01*
X1676728Y995281D01*
X1677020Y995198D01*
X1677228Y994906D01*
X1677311Y994615D01*
Y994240D01*
G01Y994615D02*
X1677436Y994865D01*
X1677645Y995073D01*
X1677895Y995156D01*
X1678145Y995073D01*
X1678353Y994865D01*
X1678478Y994490D01*
X1678436Y994115D01*
X1678270Y993740D01*
G01X1677020Y996631D02*
X1677311Y996923D01*
X1677478Y997173D01*
X1677561Y997506D01*
X1677478Y997798D01*
X1677311Y998006D01*
X1677061Y998173D01*
X1676770Y998215D01*
X1676520Y998173D01*
X1676270Y998006D01*
X1676061Y997756D01*
X1675978Y997465D01*
X1676061Y997131D01*
X1676311Y996840D01*
X1676686Y996673D01*
X1677103Y996631D01*
X1677645Y996715D01*
X1677936Y996840D01*
X1678228Y997048D01*
X1678436Y997340D01*
X1678478Y997631D01*
X1678395Y997923D01*
X1678186Y998131D01*
G01X1681970Y989040D02*
X1682095Y988790D01*
X1682178Y988498D01*
Y988165D01*
X1682053Y987790D01*
X1681845Y987498D01*
X1681595Y987290D01*
X1681178Y987123D01*
X1680803Y987081D01*
X1680428Y987165D01*
X1680178Y987290D01*
X1679928Y987540D01*
X1679761Y987831D01*
X1679678Y988123D01*
Y988415D01*
X1679761Y988706D01*
X1679886Y988956D01*
X1680053Y989165D01*
G01X1680720Y990431D02*
X1681011Y990723D01*
X1681178Y990973D01*
X1681261Y991306D01*
X1681178Y991598D01*
X1681011Y991806D01*
X1680761Y991973D01*
X1680470Y992015D01*
X1680220Y991973D01*
X1679970Y991806D01*
X1679761Y991556D01*
X1679678Y991265D01*
X1679761Y990931D01*
X1680011Y990640D01*
X1680386Y990473D01*
X1680803Y990431D01*
X1681345Y990515D01*
X1681636Y990640D01*
X1681928Y990848D01*
X1682136Y991140D01*
X1682178Y991431D01*
X1682095Y991723D01*
X1681886Y991931D01*
G01X1680178Y993406D02*
X1679886Y993656D01*
X1679720Y993990D01*
X1679678Y994365D01*
X1679720Y994698D01*
X1679928Y995031D01*
X1680178Y995240D01*
X1680428Y995281D01*
X1680720Y995198D01*
X1680928Y994906D01*
X1681011Y994615D01*
Y994240D01*
G01Y994615D02*
X1681136Y994865D01*
X1681345Y995073D01*
X1681595Y995156D01*
X1681845Y995073D01*
X1682053Y994865D01*
X1682178Y994490D01*
X1682136Y994115D01*
X1681970Y993740D01*
G01X1680053Y996506D02*
X1679845Y996756D01*
X1679720Y997048D01*
X1679678Y997423D01*
X1679761Y997798D01*
X1679928Y998090D01*
X1680220Y998298D01*
X1680553Y998340D01*
X1680886Y998256D01*
X1681095Y998048D01*
X1681261Y997756D01*
X1681303Y997465D01*
X1681261Y997173D01*
X1681095Y996798D01*
X1682178Y996923D01*
Y998048D01*
G01X1685670Y989040D02*
X1685795Y988790D01*
X1685878Y988498D01*
Y988165D01*
X1685753Y987790D01*
X1685545Y987498D01*
X1685295Y987290D01*
X1684878Y987123D01*
X1684503Y987081D01*
X1684128Y987165D01*
X1683878Y987290D01*
X1683628Y987540D01*
X1683461Y987831D01*
X1683378Y988123D01*
Y988415D01*
X1683461Y988706D01*
X1683586Y988956D01*
X1683753Y989165D01*
G01X1684420Y990431D02*
X1684711Y990723D01*
X1684878Y990973D01*
X1684961Y991306D01*
X1684878Y991598D01*
X1684711Y991806D01*
X1684461Y991973D01*
X1684170Y992015D01*
X1683920Y991973D01*
X1683670Y991806D01*
X1683461Y991556D01*
X1683378Y991265D01*
X1683461Y990931D01*
X1683711Y990640D01*
X1684086Y990473D01*
X1684503Y990431D01*
X1685045Y990515D01*
X1685336Y990640D01*
X1685628Y990848D01*
X1685836Y991140D01*
X1685878Y991431D01*
X1685795Y991723D01*
X1685586Y991931D01*
G01X1683878Y993406D02*
X1683586Y993656D01*
X1683420Y993990D01*
X1683378Y994365D01*
X1683420Y994698D01*
X1683628Y995031D01*
X1683878Y995240D01*
X1684128Y995281D01*
X1684420Y995198D01*
X1684628Y994906D01*
X1684711Y994615D01*
Y994240D01*
G01Y994615D02*
X1684836Y994865D01*
X1685045Y995073D01*
X1685295Y995156D01*
X1685545Y995073D01*
X1685753Y994865D01*
X1685878Y994490D01*
X1685836Y994115D01*
X1685670Y993740D01*
G01X1683878Y996506D02*
X1683586Y996756D01*
X1683420Y997090D01*
X1683378Y997465D01*
X1683420Y997798D01*
X1683628Y998131D01*
X1683878Y998340D01*
X1684128Y998381D01*
X1684420Y998298D01*
X1684628Y998006D01*
X1684711Y997715D01*
Y997340D01*
G01Y997715D02*
X1684836Y997965D01*
X1685045Y998173D01*
X1685295Y998256D01*
X1685545Y998173D01*
X1685753Y997965D01*
X1685878Y997590D01*
X1685836Y997215D01*
X1685670Y996840D01*
G01X1701066Y1014589D02*
X1703566D01*
Y1015630D01*
X1703441Y1015964D01*
X1703274Y1016172D01*
X1702941Y1016255D01*
X1702608Y1016172D01*
X1702399Y1015922D01*
X1702274Y1015630D01*
Y1014589D01*
G01Y1015630D02*
X1701066Y1016255D01*
G01Y1018522D02*
X1703566D01*
X1703066Y1018022D01*
G01X1701066D02*
Y1019022D01*
G01X1703149Y1020830D02*
X1703399Y1021080D01*
X1703524Y1021372D01*
X1703566Y1021705D01*
X1703483Y1022122D01*
X1703274Y1022414D01*
X1703024Y1022497D01*
X1702774Y1022455D01*
X1702566Y1022289D01*
X1702149Y1021455D01*
X1701858Y1021080D01*
X1701441Y1020830D01*
X1701066Y1020747D01*
Y1022497D01*
G01Y1025222D02*
X1703566D01*
X1701774Y1023680D01*
Y1025764D01*
G01X1701441Y1026905D02*
X1701233Y1027155D01*
X1701108Y1027447D01*
X1701066Y1027822D01*
X1701149Y1028197D01*
X1701316Y1028489D01*
X1701608Y1028697D01*
X1701941Y1028739D01*
X1702274Y1028655D01*
X1702483Y1028447D01*
X1702649Y1028155D01*
X1702691Y1027864D01*
X1702649Y1027572D01*
X1702483Y1027197D01*
X1703566Y1027322D01*
Y1028447D01*
G01X1689370Y989040D02*
X1689495Y988790D01*
X1689578Y988498D01*
Y988165D01*
X1689453Y987790D01*
X1689245Y987498D01*
X1688995Y987290D01*
X1688578Y987123D01*
X1688203Y987081D01*
X1687828Y987165D01*
X1687578Y987290D01*
X1687328Y987540D01*
X1687161Y987831D01*
X1687078Y988123D01*
Y988415D01*
X1687161Y988706D01*
X1687286Y988956D01*
X1687453Y989165D01*
G01X1688120Y990431D02*
X1688411Y990723D01*
X1688578Y990973D01*
X1688661Y991306D01*
X1688578Y991598D01*
X1688411Y991806D01*
X1688161Y991973D01*
X1687870Y992015D01*
X1687620Y991973D01*
X1687370Y991806D01*
X1687161Y991556D01*
X1687078Y991265D01*
X1687161Y990931D01*
X1687411Y990640D01*
X1687786Y990473D01*
X1688203Y990431D01*
X1688745Y990515D01*
X1689036Y990640D01*
X1689328Y990848D01*
X1689536Y991140D01*
X1689578Y991431D01*
X1689495Y991723D01*
X1689286Y991931D01*
G01X1687578Y993406D02*
X1687286Y993656D01*
X1687120Y993990D01*
X1687078Y994365D01*
X1687120Y994698D01*
X1687328Y995031D01*
X1687578Y995240D01*
X1687828Y995281D01*
X1688120Y995198D01*
X1688328Y994906D01*
X1688411Y994615D01*
Y994240D01*
G01Y994615D02*
X1688536Y994865D01*
X1688745Y995073D01*
X1688995Y995156D01*
X1689245Y995073D01*
X1689453Y994865D01*
X1689578Y994490D01*
X1689536Y994115D01*
X1689370Y993740D01*
G01X1687078Y997923D02*
X1689578D01*
X1687786Y996381D01*
Y998465D01*
G01X1760517Y975000D02*
Y973208D01*
X1760350Y972833D01*
X1760017Y972583D01*
X1759600Y972500D01*
X1759183Y972583D01*
X1758850Y972833D01*
X1758683Y973208D01*
Y975000D01*
G01X1757292Y974583D02*
X1757042Y974833D01*
X1756750Y974958D01*
X1756417Y975000D01*
X1756000Y974917D01*
X1755708Y974708D01*
X1755625Y974458D01*
X1755667Y974208D01*
X1755833Y974000D01*
X1756667Y973583D01*
X1757042Y973292D01*
X1757292Y972875D01*
X1757375Y972500D01*
X1755625D01*
G01X1754192Y974583D02*
X1753942Y974833D01*
X1753650Y974958D01*
X1753317Y975000D01*
X1752900Y974917D01*
X1752608Y974708D01*
X1752525Y974458D01*
X1752567Y974208D01*
X1752733Y974000D01*
X1753567Y973583D01*
X1753942Y973292D01*
X1754192Y972875D01*
X1754275Y972500D01*
X1752525D01*
G01X1748750Y977200D02*
X1743750D01*
Y982200D01*
G01X1763833Y1017366D02*
Y1019866D01*
X1762792D01*
X1762458Y1019741D01*
X1762250Y1019574D01*
X1762167Y1019241D01*
X1762250Y1018908D01*
X1762500Y1018699D01*
X1762792Y1018574D01*
X1763833D01*
G01X1762792D02*
X1762167Y1017366D01*
G01X1759900D02*
Y1019866D01*
X1760400Y1019366D01*
G01Y1017366D02*
X1759400D01*
G01X1757592Y1019449D02*
X1757342Y1019699D01*
X1757050Y1019824D01*
X1756717Y1019866D01*
X1756300Y1019783D01*
X1756008Y1019574D01*
X1755925Y1019324D01*
X1755967Y1019074D01*
X1756133Y1018866D01*
X1756967Y1018449D01*
X1757342Y1018158D01*
X1757592Y1017741D01*
X1757675Y1017366D01*
X1755925D01*
G01X1754617Y1017741D02*
X1754367Y1017533D01*
X1754075Y1017408D01*
X1753700Y1017366D01*
X1753325Y1017449D01*
X1753033Y1017616D01*
X1752825Y1017908D01*
X1752783Y1018241D01*
X1752867Y1018574D01*
X1753075Y1018783D01*
X1753367Y1018949D01*
X1753658Y1018991D01*
X1753950Y1018949D01*
X1754325Y1018783D01*
X1754200Y1019866D01*
X1753075D01*
G01X1751392Y1018408D02*
X1751100Y1018699D01*
X1750850Y1018866D01*
X1750517Y1018949D01*
X1750225Y1018866D01*
X1750017Y1018699D01*
X1749850Y1018449D01*
X1749808Y1018158D01*
X1749850Y1017908D01*
X1750017Y1017658D01*
X1750267Y1017449D01*
X1750558Y1017366D01*
X1750892Y1017449D01*
X1751183Y1017699D01*
X1751350Y1018074D01*
X1751392Y1018491D01*
X1751308Y1019033D01*
X1751183Y1019324D01*
X1750975Y1019616D01*
X1750683Y1019824D01*
X1750392Y1019866D01*
X1750100Y1019783D01*
X1749892Y1019574D01*
G01X1745100Y1006367D02*
X1747600D01*
Y1007408D01*
X1747475Y1007742D01*
X1747308Y1007950D01*
X1746975Y1008033D01*
X1746642Y1007950D01*
X1746433Y1007700D01*
X1746308Y1007408D01*
Y1006367D01*
G01Y1007408D02*
X1745100Y1008033D01*
G01Y1010300D02*
X1747600D01*
X1747100Y1009800D01*
G01X1745100D02*
Y1010800D01*
G01X1747183Y1012608D02*
X1747433Y1012858D01*
X1747558Y1013150D01*
X1747600Y1013483D01*
X1747517Y1013900D01*
X1747308Y1014192D01*
X1747058Y1014275D01*
X1746808Y1014233D01*
X1746600Y1014067D01*
X1746183Y1013233D01*
X1745892Y1012858D01*
X1745475Y1012608D01*
X1745100Y1012525D01*
Y1014275D01*
G01X1745475Y1015583D02*
X1745267Y1015833D01*
X1745142Y1016125D01*
X1745100Y1016500D01*
X1745183Y1016875D01*
X1745350Y1017167D01*
X1745642Y1017375D01*
X1745975Y1017417D01*
X1746308Y1017333D01*
X1746517Y1017125D01*
X1746683Y1016833D01*
X1746725Y1016542D01*
X1746683Y1016250D01*
X1746517Y1015875D01*
X1747600Y1016000D01*
Y1017125D01*
G01X1745392Y1018892D02*
X1745183Y1019183D01*
X1745100Y1019517D01*
X1745183Y1019850D01*
X1745433Y1020142D01*
X1745808Y1020350D01*
X1746183Y1020433D01*
X1746642D01*
X1747017Y1020350D01*
X1747350Y1020142D01*
X1747517Y1019892D01*
X1747600Y1019600D01*
X1747517Y1019267D01*
X1747350Y1019017D01*
X1747100Y1018850D01*
X1746767Y1018767D01*
X1746475Y1018850D01*
X1746183Y1019058D01*
X1746017Y1019308D01*
X1745975Y1019600D01*
X1746058Y1019933D01*
X1746267Y1020183D01*
X1746642Y1020433D01*
G01X1763541Y1005716D02*
X1759541D01*
Y1013116D01*
G01X1743750Y1000200D02*
Y1005200D01*
X1748750D01*
G01X1744757Y997106D02*
X1741757D01*
G01X1744757Y987263D02*
X1742757D01*
G01X1741100Y1006417D02*
X1743600D01*
Y1007417D01*
X1743475Y1007750D01*
X1743183Y1008000D01*
X1742850Y1008083D01*
X1742517Y1008000D01*
X1742267Y1007792D01*
X1742142Y1007417D01*
Y1006417D01*
G01X1742350Y1010600D02*
Y1011433D01*
X1741600D01*
X1741350Y1011183D01*
X1741183Y1010892D01*
X1741100Y1010475D01*
X1741183Y1010058D01*
X1741350Y1009767D01*
X1741600Y1009517D01*
X1741892Y1009350D01*
X1742225Y1009267D01*
X1742517D01*
X1742767Y1009350D01*
X1743058Y1009517D01*
X1743308Y1009767D01*
X1743475Y1010017D01*
X1743600Y1010350D01*
Y1010642D01*
X1743517Y1010975D01*
X1743350Y1011225D01*
G01X1741100Y1013450D02*
X1743600D01*
X1743100Y1012950D01*
G01X1741100D02*
Y1013950D01*
G01X1741475Y1015633D02*
X1741267Y1015883D01*
X1741142Y1016175D01*
X1741100Y1016550D01*
X1741183Y1016925D01*
X1741350Y1017217D01*
X1741642Y1017425D01*
X1741975Y1017467D01*
X1742308Y1017383D01*
X1742517Y1017175D01*
X1742683Y1016883D01*
X1742725Y1016592D01*
X1742683Y1016300D01*
X1742517Y1015925D01*
X1743600Y1016050D01*
Y1017175D01*
G01X1734551Y1019621D02*
X1734801Y1019746D01*
X1735093Y1019829D01*
X1735426D01*
X1735801Y1019704D01*
X1736093Y1019496D01*
X1736301Y1019246D01*
X1736468Y1018829D01*
X1736510Y1018454D01*
X1736426Y1018079D01*
X1736301Y1017829D01*
X1736051Y1017579D01*
X1735760Y1017412D01*
X1735468Y1017329D01*
X1735176D01*
X1734885Y1017412D01*
X1734635Y1017537D01*
X1734426Y1017704D01*
G01X1733160Y1018371D02*
X1732868Y1018662D01*
X1732618Y1018829D01*
X1732285Y1018912D01*
X1731993Y1018829D01*
X1731785Y1018662D01*
X1731618Y1018412D01*
X1731576Y1018121D01*
X1731618Y1017871D01*
X1731785Y1017621D01*
X1732035Y1017412D01*
X1732326Y1017329D01*
X1732660Y1017412D01*
X1732951Y1017662D01*
X1733118Y1018037D01*
X1733160Y1018454D01*
X1733076Y1018996D01*
X1732951Y1019287D01*
X1732743Y1019579D01*
X1732451Y1019787D01*
X1732160Y1019829D01*
X1731868Y1019746D01*
X1731660Y1019537D01*
G01X1730185Y1017829D02*
X1729935Y1017537D01*
X1729601Y1017371D01*
X1729226Y1017329D01*
X1728893Y1017371D01*
X1728560Y1017579D01*
X1728351Y1017829D01*
X1728310Y1018079D01*
X1728393Y1018371D01*
X1728685Y1018579D01*
X1728976Y1018662D01*
X1729351D01*
G01X1728976D02*
X1728726Y1018787D01*
X1728518Y1018996D01*
X1728435Y1019246D01*
X1728518Y1019496D01*
X1728726Y1019704D01*
X1729101Y1019829D01*
X1729476Y1019787D01*
X1729851Y1019621D01*
G01X1726876Y1017621D02*
X1726585Y1017412D01*
X1726251Y1017329D01*
X1725918Y1017412D01*
X1725626Y1017662D01*
X1725418Y1018037D01*
X1725335Y1018412D01*
Y1018871D01*
X1725418Y1019246D01*
X1725626Y1019579D01*
X1725876Y1019746D01*
X1726168Y1019829D01*
X1726501Y1019746D01*
X1726751Y1019579D01*
X1726918Y1019329D01*
X1727001Y1018996D01*
X1726918Y1018704D01*
X1726710Y1018412D01*
X1726460Y1018246D01*
X1726168Y1018204D01*
X1725835Y1018287D01*
X1725585Y1018496D01*
X1725335Y1018871D01*
G01X1733944Y1015816D02*
X1734194Y1015941D01*
X1734486Y1016024D01*
X1734819D01*
X1735194Y1015899D01*
X1735486Y1015691D01*
X1735694Y1015441D01*
X1735861Y1015024D01*
X1735903Y1014649D01*
X1735819Y1014274D01*
X1735694Y1014024D01*
X1735444Y1013774D01*
X1735153Y1013607D01*
X1734861Y1013524D01*
X1734569D01*
X1734278Y1013607D01*
X1734028Y1013732D01*
X1733819Y1013899D01*
G01X1732553Y1014566D02*
X1732261Y1014857D01*
X1732011Y1015024D01*
X1731678Y1015107D01*
X1731386Y1015024D01*
X1731178Y1014857D01*
X1731011Y1014607D01*
X1730969Y1014316D01*
X1731011Y1014066D01*
X1731178Y1013816D01*
X1731428Y1013607D01*
X1731719Y1013524D01*
X1732053Y1013607D01*
X1732344Y1013857D01*
X1732511Y1014232D01*
X1732553Y1014649D01*
X1732469Y1015191D01*
X1732344Y1015482D01*
X1732136Y1015774D01*
X1731844Y1015982D01*
X1731553Y1016024D01*
X1731261Y1015941D01*
X1731053Y1015732D01*
G01X1728161Y1013524D02*
Y1016024D01*
X1729703Y1014232D01*
X1727619D01*
G01X1725561Y1013524D02*
Y1016024D01*
X1726061Y1015524D01*
G01Y1013524D02*
X1725061D01*
G01X1760196Y1024217D02*
X1760446Y1024342D01*
X1760738Y1024425D01*
X1761071D01*
X1761446Y1024300D01*
X1761738Y1024092D01*
X1761946Y1023842D01*
X1762113Y1023425D01*
X1762155Y1023050D01*
X1762071Y1022675D01*
X1761946Y1022425D01*
X1761696Y1022175D01*
X1761405Y1022008D01*
X1761113Y1021925D01*
X1760821D01*
X1760530Y1022008D01*
X1760280Y1022133D01*
X1760071Y1022300D01*
G01X1758805Y1022967D02*
X1758513Y1023258D01*
X1758263Y1023425D01*
X1757930Y1023508D01*
X1757638Y1023425D01*
X1757430Y1023258D01*
X1757263Y1023008D01*
X1757221Y1022717D01*
X1757263Y1022467D01*
X1757430Y1022217D01*
X1757680Y1022008D01*
X1757971Y1021925D01*
X1758305Y1022008D01*
X1758596Y1022258D01*
X1758763Y1022633D01*
X1758805Y1023050D01*
X1758721Y1023592D01*
X1758596Y1023883D01*
X1758388Y1024175D01*
X1758096Y1024383D01*
X1757805Y1024425D01*
X1757513Y1024342D01*
X1757305Y1024133D01*
G01X1755705Y1022967D02*
X1755413Y1023258D01*
X1755163Y1023425D01*
X1754830Y1023508D01*
X1754538Y1023425D01*
X1754330Y1023258D01*
X1754163Y1023008D01*
X1754121Y1022717D01*
X1754163Y1022467D01*
X1754330Y1022217D01*
X1754580Y1022008D01*
X1754871Y1021925D01*
X1755205Y1022008D01*
X1755496Y1022258D01*
X1755663Y1022633D01*
X1755705Y1023050D01*
X1755621Y1023592D01*
X1755496Y1023883D01*
X1755288Y1024175D01*
X1754996Y1024383D01*
X1754705Y1024425D01*
X1754413Y1024342D01*
X1754205Y1024133D01*
G01X1751896Y1021925D02*
X1751813Y1022467D01*
X1751688Y1022925D01*
X1751521Y1023342D01*
X1751313Y1023800D01*
X1750980Y1024425D01*
X1752646D01*
G01X1818320Y906226D02*
Y908726D01*
X1817279D01*
X1816945Y908601D01*
X1816737Y908434D01*
X1816654Y908101D01*
X1816737Y907768D01*
X1816987Y907559D01*
X1817279Y907434D01*
X1818320D01*
G01X1817279D02*
X1816654Y906226D01*
G01X1814387D02*
Y908726D01*
X1814887Y908226D01*
G01Y906226D02*
X1813887D01*
G01X1812079Y908309D02*
X1811829Y908559D01*
X1811537Y908684D01*
X1811204Y908726D01*
X1810787Y908643D01*
X1810495Y908434D01*
X1810412Y908184D01*
X1810454Y907934D01*
X1810620Y907726D01*
X1811454Y907309D01*
X1811829Y907018D01*
X1812079Y906601D01*
X1812162Y906226D01*
X1810412D01*
G01X1808979Y907268D02*
X1808687Y907559D01*
X1808437Y907726D01*
X1808104Y907809D01*
X1807812Y907726D01*
X1807604Y907559D01*
X1807437Y907309D01*
X1807395Y907018D01*
X1807437Y906768D01*
X1807604Y906518D01*
X1807854Y906309D01*
X1808145Y906226D01*
X1808479Y906309D01*
X1808770Y906559D01*
X1808937Y906934D01*
X1808979Y907351D01*
X1808895Y907893D01*
X1808770Y908184D01*
X1808562Y908476D01*
X1808270Y908684D01*
X1807979Y908726D01*
X1807687Y908643D01*
X1807479Y908434D01*
G01X1805879Y907268D02*
X1805587Y907559D01*
X1805337Y907726D01*
X1805004Y907809D01*
X1804712Y907726D01*
X1804504Y907559D01*
X1804337Y907309D01*
X1804295Y907018D01*
X1804337Y906768D01*
X1804504Y906518D01*
X1804754Y906309D01*
X1805045Y906226D01*
X1805379Y906309D01*
X1805670Y906559D01*
X1805837Y906934D01*
X1805879Y907351D01*
X1805795Y907893D01*
X1805670Y908184D01*
X1805462Y908476D01*
X1805170Y908684D01*
X1804879Y908726D01*
X1804587Y908643D01*
X1804379Y908434D01*
G01X1771450Y982200D02*
Y977200D01*
X1766450D01*
G01X1770443Y983326D02*
X1773443D01*
G01X1798883Y956500D02*
Y954000D01*
X1797217D01*
G01X1795742Y955042D02*
X1795450Y955333D01*
X1795200Y955500D01*
X1794867Y955583D01*
X1794575Y955500D01*
X1794367Y955333D01*
X1794200Y955083D01*
X1794158Y954792D01*
X1794200Y954542D01*
X1794367Y954292D01*
X1794617Y954083D01*
X1794908Y954000D01*
X1795242Y954083D01*
X1795533Y954333D01*
X1795700Y954708D01*
X1795742Y955125D01*
X1795658Y955667D01*
X1795533Y955958D01*
X1795325Y956250D01*
X1795033Y956458D01*
X1794742Y956500D01*
X1794450Y956417D01*
X1794242Y956208D01*
G01X1772100Y1000800D02*
Y959400D01*
X1822700D01*
Y1000800D01*
X1772100D01*
G01X1765400Y1007700D02*
Y1011700D01*
X1772800D01*
G01X1802336Y1002641D02*
X1804836D01*
Y1003682D01*
X1804711Y1004016D01*
X1804544Y1004224D01*
X1804211Y1004307D01*
X1803878Y1004224D01*
X1803669Y1003974D01*
X1803544Y1003682D01*
Y1002641D01*
G01Y1003682D02*
X1802336Y1004307D01*
G01Y1006574D02*
X1804836D01*
X1804336Y1006074D01*
G01X1802336D02*
Y1007074D01*
G01X1804419Y1008882D02*
X1804669Y1009132D01*
X1804794Y1009424D01*
X1804836Y1009757D01*
X1804753Y1010174D01*
X1804544Y1010466D01*
X1804294Y1010549D01*
X1804044Y1010507D01*
X1803836Y1010341D01*
X1803419Y1009507D01*
X1803128Y1009132D01*
X1802711Y1008882D01*
X1802336Y1008799D01*
Y1010549D01*
G01Y1013274D02*
X1804836D01*
X1803044Y1011732D01*
Y1013816D01*
G01X1802628Y1015166D02*
X1802419Y1015457D01*
X1802336Y1015791D01*
X1802419Y1016124D01*
X1802669Y1016416D01*
X1803044Y1016624D01*
X1803419Y1016707D01*
X1803878D01*
X1804253Y1016624D01*
X1804586Y1016416D01*
X1804753Y1016166D01*
X1804836Y1015874D01*
X1804753Y1015541D01*
X1804586Y1015291D01*
X1804336Y1015124D01*
X1804003Y1015041D01*
X1803711Y1015124D01*
X1803419Y1015332D01*
X1803253Y1015582D01*
X1803211Y1015874D01*
X1803294Y1016207D01*
X1803503Y1016457D01*
X1803878Y1016707D01*
G01X1795336Y1003974D02*
X1791336D01*
Y1011374D01*
G01X1770443Y993169D02*
X1772443D01*
G01X1780633Y1017567D02*
Y1020067D01*
X1779592D01*
X1779258Y1019942D01*
X1779050Y1019775D01*
X1778967Y1019442D01*
X1779050Y1019109D01*
X1779300Y1018900D01*
X1779592Y1018775D01*
X1780633D01*
G01X1779592D02*
X1778967Y1017567D01*
G01X1776700D02*
Y1020067D01*
X1777200Y1019567D01*
G01Y1017567D02*
X1776200D01*
G01X1774392Y1019650D02*
X1774142Y1019900D01*
X1773850Y1020025D01*
X1773517Y1020067D01*
X1773100Y1019984D01*
X1772808Y1019775D01*
X1772725Y1019525D01*
X1772767Y1019275D01*
X1772933Y1019067D01*
X1773767Y1018650D01*
X1774142Y1018359D01*
X1774392Y1017942D01*
X1774475Y1017567D01*
X1772725D01*
G01X1771417Y1017942D02*
X1771167Y1017734D01*
X1770875Y1017609D01*
X1770500Y1017567D01*
X1770125Y1017650D01*
X1769833Y1017817D01*
X1769625Y1018109D01*
X1769583Y1018442D01*
X1769667Y1018775D01*
X1769875Y1018984D01*
X1770167Y1019150D01*
X1770458Y1019192D01*
X1770750Y1019150D01*
X1771125Y1018984D01*
X1771000Y1020067D01*
X1769875D01*
G01X1766900Y1017567D02*
Y1020067D01*
X1768442Y1018275D01*
X1766358D01*
G01X1809292Y1004767D02*
X1809417Y1004517D01*
X1809500Y1004225D01*
Y1003892D01*
X1809375Y1003517D01*
X1809167Y1003225D01*
X1808917Y1003017D01*
X1808500Y1002850D01*
X1808125Y1002808D01*
X1807750Y1002892D01*
X1807500Y1003017D01*
X1807250Y1003267D01*
X1807083Y1003558D01*
X1807000Y1003850D01*
Y1004142D01*
X1807083Y1004433D01*
X1807208Y1004683D01*
X1807375Y1004892D01*
G01X1808042Y1006158D02*
X1808333Y1006450D01*
X1808500Y1006700D01*
X1808583Y1007033D01*
X1808500Y1007325D01*
X1808333Y1007533D01*
X1808083Y1007700D01*
X1807792Y1007742D01*
X1807542Y1007700D01*
X1807292Y1007533D01*
X1807083Y1007283D01*
X1807000Y1006992D01*
X1807083Y1006658D01*
X1807333Y1006367D01*
X1807708Y1006200D01*
X1808125Y1006158D01*
X1808667Y1006242D01*
X1808958Y1006367D01*
X1809250Y1006575D01*
X1809458Y1006867D01*
X1809500Y1007158D01*
X1809417Y1007450D01*
X1809208Y1007658D01*
G01X1807000Y1010550D02*
X1809500D01*
X1807708Y1009008D01*
Y1011092D01*
G01X1809083Y1012358D02*
X1809333Y1012608D01*
X1809458Y1012900D01*
X1809500Y1013233D01*
X1809417Y1013650D01*
X1809208Y1013942D01*
X1808958Y1014025D01*
X1808708Y1013983D01*
X1808500Y1013817D01*
X1808083Y1012983D01*
X1807792Y1012608D01*
X1807375Y1012358D01*
X1807000Y1012275D01*
Y1014025D01*
G01X1811233Y1020792D02*
X1811483Y1020917D01*
X1811775Y1021000D01*
X1812108D01*
X1812483Y1020875D01*
X1812775Y1020667D01*
X1812983Y1020417D01*
X1813150Y1020000D01*
X1813192Y1019625D01*
X1813108Y1019250D01*
X1812983Y1019000D01*
X1812733Y1018750D01*
X1812442Y1018583D01*
X1812150Y1018500D01*
X1811858D01*
X1811567Y1018583D01*
X1811317Y1018708D01*
X1811108Y1018875D01*
G01X1809842Y1019542D02*
X1809550Y1019833D01*
X1809300Y1020000D01*
X1808967Y1020083D01*
X1808675Y1020000D01*
X1808467Y1019833D01*
X1808300Y1019583D01*
X1808258Y1019292D01*
X1808300Y1019042D01*
X1808467Y1018792D01*
X1808717Y1018583D01*
X1809008Y1018500D01*
X1809342Y1018583D01*
X1809633Y1018833D01*
X1809800Y1019208D01*
X1809842Y1019625D01*
X1809758Y1020167D01*
X1809633Y1020458D01*
X1809425Y1020750D01*
X1809133Y1020958D01*
X1808842Y1021000D01*
X1808550Y1020917D01*
X1808342Y1020708D01*
G01X1805450Y1018500D02*
Y1021000D01*
X1806992Y1019208D01*
X1804908D01*
G01X1803767Y1019000D02*
X1803517Y1018708D01*
X1803183Y1018542D01*
X1802808Y1018500D01*
X1802475Y1018542D01*
X1802142Y1018750D01*
X1801933Y1019000D01*
X1801892Y1019250D01*
X1801975Y1019542D01*
X1802267Y1019750D01*
X1802558Y1019833D01*
X1802933D01*
G01X1802558D02*
X1802308Y1019958D01*
X1802100Y1020167D01*
X1802017Y1020417D01*
X1802100Y1020667D01*
X1802308Y1020875D01*
X1802683Y1021000D01*
X1803058Y1020958D01*
X1803433Y1020792D01*
G01X1832577Y833622D02*
X1830077D01*
G01X1832577Y832664D02*
Y834580D01*
G01X1832369Y837639D02*
X1832494Y837389D01*
X1832577Y837097D01*
Y836764D01*
X1832452Y836389D01*
X1832244Y836097D01*
X1831994Y835889D01*
X1831577Y835722D01*
X1831202Y835680D01*
X1830827Y835764D01*
X1830577Y835889D01*
X1830327Y836139D01*
X1830160Y836430D01*
X1830077Y836722D01*
Y837014D01*
X1830160Y837305D01*
X1830285Y837555D01*
X1830452Y837764D01*
G01X1830077Y839822D02*
X1832577D01*
X1832077Y839322D01*
G01X1830077D02*
Y840322D01*
G01X1832160Y842130D02*
X1832410Y842380D01*
X1832535Y842672D01*
X1832577Y843005D01*
X1832494Y843422D01*
X1832285Y843714D01*
X1832035Y843797D01*
X1831785Y843755D01*
X1831577Y843589D01*
X1831160Y842755D01*
X1830869Y842380D01*
X1830452Y842130D01*
X1830077Y842047D01*
Y843797D01*
G01X1834893Y830032D02*
X1846093D01*
G01X1834893Y848032D02*
Y830032D01*
G01X1863040Y795775D02*
Y798275D01*
X1862040D01*
X1861707Y798150D01*
X1861457Y797858D01*
X1861374Y797525D01*
X1861457Y797192D01*
X1861665Y796942D01*
X1862040Y796817D01*
X1863040D01*
G01X1858857Y797025D02*
X1858024D01*
Y796275D01*
X1858274Y796025D01*
X1858565Y795858D01*
X1858982Y795775D01*
X1859399Y795858D01*
X1859690Y796025D01*
X1859940Y796275D01*
X1860107Y796567D01*
X1860190Y796900D01*
Y797192D01*
X1860107Y797442D01*
X1859940Y797733D01*
X1859690Y797983D01*
X1859440Y798150D01*
X1859107Y798275D01*
X1858815D01*
X1858482Y798192D01*
X1858232Y798025D01*
G01X1856007Y795775D02*
Y798275D01*
X1856507Y797775D01*
G01Y795775D02*
X1855507D01*
G01X1853699Y796817D02*
X1853407Y797108D01*
X1853157Y797275D01*
X1852824Y797358D01*
X1852532Y797275D01*
X1852324Y797108D01*
X1852157Y796858D01*
X1852115Y796567D01*
X1852157Y796317D01*
X1852324Y796067D01*
X1852574Y795858D01*
X1852865Y795775D01*
X1853199Y795858D01*
X1853490Y796108D01*
X1853657Y796483D01*
X1853699Y796900D01*
X1853615Y797442D01*
X1853490Y797733D01*
X1853282Y798025D01*
X1852990Y798233D01*
X1852699Y798275D01*
X1852407Y798192D01*
X1852199Y797983D01*
G01X1843845Y813389D02*
X1844095Y813514D01*
X1844387Y813597D01*
X1844720D01*
X1845095Y813472D01*
X1845387Y813264D01*
X1845595Y813014D01*
X1845762Y812597D01*
X1845804Y812222D01*
X1845720Y811847D01*
X1845595Y811597D01*
X1845345Y811347D01*
X1845054Y811180D01*
X1844762Y811097D01*
X1844470D01*
X1844179Y811180D01*
X1843929Y811305D01*
X1843720Y811472D01*
G01X1842454Y812139D02*
X1842162Y812430D01*
X1841912Y812597D01*
X1841579Y812680D01*
X1841287Y812597D01*
X1841079Y812430D01*
X1840912Y812180D01*
X1840870Y811889D01*
X1840912Y811639D01*
X1841079Y811389D01*
X1841329Y811180D01*
X1841620Y811097D01*
X1841954Y811180D01*
X1842245Y811430D01*
X1842412Y811805D01*
X1842454Y812222D01*
X1842370Y812764D01*
X1842245Y813055D01*
X1842037Y813347D01*
X1841745Y813555D01*
X1841454Y813597D01*
X1841162Y813514D01*
X1840954Y813305D01*
G01X1839354Y812139D02*
X1839062Y812430D01*
X1838812Y812597D01*
X1838479Y812680D01*
X1838187Y812597D01*
X1837979Y812430D01*
X1837812Y812180D01*
X1837770Y811889D01*
X1837812Y811639D01*
X1837979Y811389D01*
X1838229Y811180D01*
X1838520Y811097D01*
X1838854Y811180D01*
X1839145Y811430D01*
X1839312Y811805D01*
X1839354Y812222D01*
X1839270Y812764D01*
X1839145Y813055D01*
X1838937Y813347D01*
X1838645Y813555D01*
X1838354Y813597D01*
X1838062Y813514D01*
X1837854Y813305D01*
G01X1834962Y811097D02*
Y813597D01*
X1836504Y811805D01*
X1834420D01*
G01X1843845Y817089D02*
X1844095Y817214D01*
X1844387Y817297D01*
X1844720D01*
X1845095Y817172D01*
X1845387Y816964D01*
X1845595Y816714D01*
X1845762Y816297D01*
X1845804Y815922D01*
X1845720Y815547D01*
X1845595Y815297D01*
X1845345Y815047D01*
X1845054Y814880D01*
X1844762Y814797D01*
X1844470D01*
X1844179Y814880D01*
X1843929Y815005D01*
X1843720Y815172D01*
G01X1842454Y815839D02*
X1842162Y816130D01*
X1841912Y816297D01*
X1841579Y816380D01*
X1841287Y816297D01*
X1841079Y816130D01*
X1840912Y815880D01*
X1840870Y815589D01*
X1840912Y815339D01*
X1841079Y815089D01*
X1841329Y814880D01*
X1841620Y814797D01*
X1841954Y814880D01*
X1842245Y815130D01*
X1842412Y815505D01*
X1842454Y815922D01*
X1842370Y816464D01*
X1842245Y816755D01*
X1842037Y817047D01*
X1841745Y817255D01*
X1841454Y817297D01*
X1841162Y817214D01*
X1840954Y817005D01*
G01X1839354Y815839D02*
X1839062Y816130D01*
X1838812Y816297D01*
X1838479Y816380D01*
X1838187Y816297D01*
X1837979Y816130D01*
X1837812Y815880D01*
X1837770Y815589D01*
X1837812Y815339D01*
X1837979Y815089D01*
X1838229Y814880D01*
X1838520Y814797D01*
X1838854Y814880D01*
X1839145Y815130D01*
X1839312Y815505D01*
X1839354Y815922D01*
X1839270Y816464D01*
X1839145Y816755D01*
X1838937Y817047D01*
X1838645Y817255D01*
X1838354Y817297D01*
X1838062Y817214D01*
X1837854Y817005D01*
G01X1836379Y815297D02*
X1836129Y815005D01*
X1835795Y814839D01*
X1835420Y814797D01*
X1835087Y814839D01*
X1834754Y815047D01*
X1834545Y815297D01*
X1834504Y815547D01*
X1834587Y815839D01*
X1834879Y816047D01*
X1835170Y816130D01*
X1835545D01*
G01X1835170D02*
X1834920Y816255D01*
X1834712Y816464D01*
X1834629Y816714D01*
X1834712Y816964D01*
X1834920Y817172D01*
X1835295Y817297D01*
X1835670Y817255D01*
X1836045Y817089D01*
G01X1843845Y820789D02*
X1844095Y820914D01*
X1844387Y820997D01*
X1844720D01*
X1845095Y820872D01*
X1845387Y820664D01*
X1845595Y820414D01*
X1845762Y819997D01*
X1845804Y819622D01*
X1845720Y819247D01*
X1845595Y818997D01*
X1845345Y818747D01*
X1845054Y818580D01*
X1844762Y818497D01*
X1844470D01*
X1844179Y818580D01*
X1843929Y818705D01*
X1843720Y818872D01*
G01X1842454Y819539D02*
X1842162Y819830D01*
X1841912Y819997D01*
X1841579Y820080D01*
X1841287Y819997D01*
X1841079Y819830D01*
X1840912Y819580D01*
X1840870Y819289D01*
X1840912Y819039D01*
X1841079Y818789D01*
X1841329Y818580D01*
X1841620Y818497D01*
X1841954Y818580D01*
X1842245Y818830D01*
X1842412Y819205D01*
X1842454Y819622D01*
X1842370Y820164D01*
X1842245Y820455D01*
X1842037Y820747D01*
X1841745Y820955D01*
X1841454Y820997D01*
X1841162Y820914D01*
X1840954Y820705D01*
G01X1839354Y819539D02*
X1839062Y819830D01*
X1838812Y819997D01*
X1838479Y820080D01*
X1838187Y819997D01*
X1837979Y819830D01*
X1837812Y819580D01*
X1837770Y819289D01*
X1837812Y819039D01*
X1837979Y818789D01*
X1838229Y818580D01*
X1838520Y818497D01*
X1838854Y818580D01*
X1839145Y818830D01*
X1839312Y819205D01*
X1839354Y819622D01*
X1839270Y820164D01*
X1839145Y820455D01*
X1838937Y820747D01*
X1838645Y820955D01*
X1838354Y820997D01*
X1838062Y820914D01*
X1837854Y820705D01*
G01X1836254Y820580D02*
X1836004Y820830D01*
X1835712Y820955D01*
X1835379Y820997D01*
X1834962Y820914D01*
X1834670Y820705D01*
X1834587Y820455D01*
X1834629Y820205D01*
X1834795Y819997D01*
X1835629Y819580D01*
X1836004Y819289D01*
X1836254Y818872D01*
X1836337Y818497D01*
X1834587D01*
G01X1846093Y848032D02*
X1834893D01*
G01X1833525Y872929D02*
X1831025D01*
Y874595D01*
G01Y876862D02*
X1831067Y877154D01*
X1831192Y877487D01*
X1831400Y877695D01*
X1831692Y877779D01*
X1831983Y877695D01*
X1832233Y877445D01*
X1832358Y877070D01*
Y876654D01*
X1832442Y876404D01*
X1832650Y876195D01*
X1832942Y876112D01*
X1833233Y876237D01*
X1833442Y876529D01*
X1833525Y876862D01*
X1833442Y877195D01*
X1833233Y877487D01*
X1832942Y877612D01*
X1832650Y877529D01*
X1832442Y877320D01*
X1832358Y877070D01*
Y876654D01*
X1832233Y876279D01*
X1831983Y876029D01*
X1831692Y875945D01*
X1831400Y876029D01*
X1831192Y876237D01*
X1831067Y876570D01*
X1831025Y876862D01*
G01X1877876Y901559D02*
X1836476D01*
Y850959D01*
X1877876D01*
Y901559D01*
G01X1838150Y938500D02*
Y936000D01*
G01X1839108Y938500D02*
X1837192D01*
G01X1834133Y938292D02*
X1834383Y938417D01*
X1834675Y938500D01*
X1835008D01*
X1835383Y938375D01*
X1835675Y938167D01*
X1835883Y937917D01*
X1836050Y937500D01*
X1836092Y937125D01*
X1836008Y936750D01*
X1835883Y936500D01*
X1835633Y936250D01*
X1835342Y936083D01*
X1835050Y936000D01*
X1834758D01*
X1834467Y936083D01*
X1834217Y936208D01*
X1834008Y936375D01*
G01X1831950Y936000D02*
Y938500D01*
X1832450Y938000D01*
G01Y936000D02*
X1831450D01*
G01X1828850D02*
Y938500D01*
X1829350Y938000D01*
G01Y936000D02*
X1828350D01*
G01X1852579Y926277D02*
Y924485D01*
X1852412Y924110D01*
X1852079Y923860D01*
X1851662Y923777D01*
X1851245Y923860D01*
X1850912Y924110D01*
X1850745Y924485D01*
Y926277D01*
G01X1849354Y925860D02*
X1849104Y926110D01*
X1848812Y926235D01*
X1848479Y926277D01*
X1848062Y926194D01*
X1847770Y925985D01*
X1847687Y925735D01*
X1847729Y925485D01*
X1847895Y925277D01*
X1848729Y924860D01*
X1849104Y924569D01*
X1849354Y924152D01*
X1849437Y923777D01*
X1847687D01*
G01X1845545D02*
X1845462Y924319D01*
X1845337Y924777D01*
X1845170Y925194D01*
X1844962Y925652D01*
X1844629Y926277D01*
X1846295D01*
G01X1854276Y924909D02*
Y929909D01*
X1859276D01*
G01Y902209D02*
X1854276D01*
Y907209D01*
G01X1860402Y903216D02*
Y900216D01*
G01X1837536Y917610D02*
Y920110D01*
X1836495D01*
X1836161Y919985D01*
X1835953Y919818D01*
X1835870Y919485D01*
X1835953Y919152D01*
X1836203Y918943D01*
X1836495Y918818D01*
X1837536D01*
G01X1836495D02*
X1835870Y917610D01*
G01X1833603D02*
Y920110D01*
X1834103Y919610D01*
G01Y917610D02*
X1833103D01*
G01X1831295Y919693D02*
X1831045Y919943D01*
X1830753Y920068D01*
X1830420Y920110D01*
X1830003Y920027D01*
X1829711Y919818D01*
X1829628Y919568D01*
X1829670Y919318D01*
X1829836Y919110D01*
X1830670Y918693D01*
X1831045Y918402D01*
X1831295Y917985D01*
X1831378Y917610D01*
X1829628D01*
G01X1828195Y918652D02*
X1827903Y918943D01*
X1827653Y919110D01*
X1827320Y919193D01*
X1827028Y919110D01*
X1826820Y918943D01*
X1826653Y918693D01*
X1826611Y918402D01*
X1826653Y918152D01*
X1826820Y917902D01*
X1827070Y917693D01*
X1827361Y917610D01*
X1827695Y917693D01*
X1827986Y917943D01*
X1828153Y918318D01*
X1828195Y918735D01*
X1828111Y919277D01*
X1827986Y919568D01*
X1827778Y919860D01*
X1827486Y920068D01*
X1827195Y920110D01*
X1826903Y920027D01*
X1826695Y919818D01*
G01X1825011Y917902D02*
X1824720Y917693D01*
X1824386Y917610D01*
X1824053Y917693D01*
X1823761Y917943D01*
X1823553Y918318D01*
X1823470Y918693D01*
Y919152D01*
X1823553Y919527D01*
X1823761Y919860D01*
X1824011Y920027D01*
X1824303Y920110D01*
X1824636Y920027D01*
X1824886Y919860D01*
X1825053Y919610D01*
X1825136Y919277D01*
X1825053Y918985D01*
X1824845Y918693D01*
X1824595Y918527D01*
X1824303Y918485D01*
X1823970Y918568D01*
X1823720Y918777D01*
X1823470Y919152D01*
G01X1840300Y915000D02*
X1845500D01*
G01X1840300Y922000D02*
X1848100D01*
G01X1840300Y915000D02*
Y922000D01*
G01X1853700Y915000D02*
X1845000D01*
G01X1853700Y922000D02*
Y915000D01*
G01X1847300Y922000D02*
X1853700D01*
G01X1840399Y926078D02*
X1840649Y926203D01*
X1840941Y926286D01*
X1841274D01*
X1841649Y926161D01*
X1841941Y925953D01*
X1842149Y925703D01*
X1842316Y925286D01*
X1842358Y924911D01*
X1842274Y924536D01*
X1842149Y924286D01*
X1841899Y924036D01*
X1841608Y923869D01*
X1841316Y923786D01*
X1841024D01*
X1840733Y923869D01*
X1840483Y923994D01*
X1840274Y924161D01*
G01X1839008Y924828D02*
X1838716Y925119D01*
X1838466Y925286D01*
X1838133Y925369D01*
X1837841Y925286D01*
X1837633Y925119D01*
X1837466Y924869D01*
X1837424Y924578D01*
X1837466Y924328D01*
X1837633Y924078D01*
X1837883Y923869D01*
X1838174Y923786D01*
X1838508Y923869D01*
X1838799Y924119D01*
X1838966Y924494D01*
X1839008Y924911D01*
X1838924Y925453D01*
X1838799Y925744D01*
X1838591Y926036D01*
X1838299Y926244D01*
X1838008Y926286D01*
X1837716Y926203D01*
X1837508Y925994D01*
G01X1836033Y924161D02*
X1835783Y923953D01*
X1835491Y923828D01*
X1835116Y923786D01*
X1834741Y923869D01*
X1834449Y924036D01*
X1834241Y924328D01*
X1834199Y924661D01*
X1834283Y924994D01*
X1834491Y925203D01*
X1834783Y925369D01*
X1835074Y925411D01*
X1835366Y925369D01*
X1835741Y925203D01*
X1835616Y926286D01*
X1834491D01*
G01X1832933Y924286D02*
X1832683Y923994D01*
X1832349Y923828D01*
X1831974Y923786D01*
X1831641Y923828D01*
X1831308Y924036D01*
X1831099Y924286D01*
X1831058Y924536D01*
X1831141Y924828D01*
X1831433Y925036D01*
X1831724Y925119D01*
X1832099D01*
G01X1831724D02*
X1831474Y925244D01*
X1831266Y925453D01*
X1831183Y925703D01*
X1831266Y925953D01*
X1831474Y926161D01*
X1831849Y926286D01*
X1832224Y926244D01*
X1832599Y926078D01*
G01X1840399Y929778D02*
X1840649Y929903D01*
X1840941Y929986D01*
X1841274D01*
X1841649Y929861D01*
X1841941Y929653D01*
X1842149Y929403D01*
X1842316Y928986D01*
X1842358Y928611D01*
X1842274Y928236D01*
X1842149Y927986D01*
X1841899Y927736D01*
X1841608Y927569D01*
X1841316Y927486D01*
X1841024D01*
X1840733Y927569D01*
X1840483Y927694D01*
X1840274Y927861D01*
G01X1839008Y928528D02*
X1838716Y928819D01*
X1838466Y928986D01*
X1838133Y929069D01*
X1837841Y928986D01*
X1837633Y928819D01*
X1837466Y928569D01*
X1837424Y928278D01*
X1837466Y928028D01*
X1837633Y927778D01*
X1837883Y927569D01*
X1838174Y927486D01*
X1838508Y927569D01*
X1838799Y927819D01*
X1838966Y928194D01*
X1839008Y928611D01*
X1838924Y929153D01*
X1838799Y929444D01*
X1838591Y929736D01*
X1838299Y929944D01*
X1838008Y929986D01*
X1837716Y929903D01*
X1837508Y929694D01*
G01X1836033Y927861D02*
X1835783Y927653D01*
X1835491Y927528D01*
X1835116Y927486D01*
X1834741Y927569D01*
X1834449Y927736D01*
X1834241Y928028D01*
X1834199Y928361D01*
X1834283Y928694D01*
X1834491Y928903D01*
X1834783Y929069D01*
X1835074Y929111D01*
X1835366Y929069D01*
X1835741Y928903D01*
X1835616Y929986D01*
X1834491D01*
G01X1832808Y929569D02*
X1832558Y929819D01*
X1832266Y929944D01*
X1831933Y929986D01*
X1831516Y929903D01*
X1831224Y929694D01*
X1831141Y929444D01*
X1831183Y929194D01*
X1831349Y928986D01*
X1832183Y928569D01*
X1832558Y928278D01*
X1832808Y927861D01*
X1832891Y927486D01*
X1831141D01*
G01X1840399Y933478D02*
X1840649Y933603D01*
X1840941Y933686D01*
X1841274D01*
X1841649Y933561D01*
X1841941Y933353D01*
X1842149Y933103D01*
X1842316Y932686D01*
X1842358Y932311D01*
X1842274Y931936D01*
X1842149Y931686D01*
X1841899Y931436D01*
X1841608Y931269D01*
X1841316Y931186D01*
X1841024D01*
X1840733Y931269D01*
X1840483Y931394D01*
X1840274Y931561D01*
G01X1839008Y932228D02*
X1838716Y932519D01*
X1838466Y932686D01*
X1838133Y932769D01*
X1837841Y932686D01*
X1837633Y932519D01*
X1837466Y932269D01*
X1837424Y931978D01*
X1837466Y931728D01*
X1837633Y931478D01*
X1837883Y931269D01*
X1838174Y931186D01*
X1838508Y931269D01*
X1838799Y931519D01*
X1838966Y931894D01*
X1839008Y932311D01*
X1838924Y932853D01*
X1838799Y933144D01*
X1838591Y933436D01*
X1838299Y933644D01*
X1838008Y933686D01*
X1837716Y933603D01*
X1837508Y933394D01*
G01X1834616Y931186D02*
Y933686D01*
X1836158Y931894D01*
X1834074D01*
G01X1832016Y931186D02*
X1831724Y931228D01*
X1831391Y931353D01*
X1831183Y931561D01*
X1831099Y931853D01*
X1831183Y932144D01*
X1831433Y932394D01*
X1831808Y932519D01*
X1832224D01*
X1832474Y932603D01*
X1832683Y932811D01*
X1832766Y933103D01*
X1832641Y933394D01*
X1832349Y933603D01*
X1832016Y933686D01*
X1831683Y933603D01*
X1831391Y933394D01*
X1831266Y933103D01*
X1831349Y932811D01*
X1831558Y932603D01*
X1831808Y932519D01*
X1832224D01*
X1832599Y932394D01*
X1832849Y932144D01*
X1832933Y931853D01*
X1832849Y931561D01*
X1832641Y931353D01*
X1832308Y931228D01*
X1832016Y931186D01*
G01X1830788Y903610D02*
X1831038Y903735D01*
X1831330Y903818D01*
X1831663D01*
X1832038Y903693D01*
X1832330Y903485D01*
X1832538Y903235D01*
X1832705Y902818D01*
X1832747Y902443D01*
X1832663Y902068D01*
X1832538Y901818D01*
X1832288Y901568D01*
X1831997Y901401D01*
X1831705Y901318D01*
X1831413D01*
X1831122Y901401D01*
X1830872Y901526D01*
X1830663Y901693D01*
G01X1829397Y902360D02*
X1829105Y902651D01*
X1828855Y902818D01*
X1828522Y902901D01*
X1828230Y902818D01*
X1828022Y902651D01*
X1827855Y902401D01*
X1827813Y902110D01*
X1827855Y901860D01*
X1828022Y901610D01*
X1828272Y901401D01*
X1828563Y901318D01*
X1828897Y901401D01*
X1829188Y901651D01*
X1829355Y902026D01*
X1829397Y902443D01*
X1829313Y902985D01*
X1829188Y903276D01*
X1828980Y903568D01*
X1828688Y903776D01*
X1828397Y903818D01*
X1828105Y903735D01*
X1827897Y903526D01*
G01X1826422Y901693D02*
X1826172Y901485D01*
X1825880Y901360D01*
X1825505Y901318D01*
X1825130Y901401D01*
X1824838Y901568D01*
X1824630Y901860D01*
X1824588Y902193D01*
X1824672Y902526D01*
X1824880Y902735D01*
X1825172Y902901D01*
X1825463Y902943D01*
X1825755Y902901D01*
X1826130Y902735D01*
X1826005Y903818D01*
X1824880D01*
G01X1822488Y901318D02*
X1822405Y901860D01*
X1822280Y902318D01*
X1822113Y902735D01*
X1821905Y903193D01*
X1821572Y903818D01*
X1823238D01*
G01X1830788Y899910D02*
X1831038Y900035D01*
X1831330Y900118D01*
X1831663D01*
X1832038Y899993D01*
X1832330Y899785D01*
X1832538Y899535D01*
X1832705Y899118D01*
X1832747Y898743D01*
X1832663Y898368D01*
X1832538Y898118D01*
X1832288Y897868D01*
X1831997Y897701D01*
X1831705Y897618D01*
X1831413D01*
X1831122Y897701D01*
X1830872Y897826D01*
X1830663Y897993D01*
G01X1829397Y898660D02*
X1829105Y898951D01*
X1828855Y899118D01*
X1828522Y899201D01*
X1828230Y899118D01*
X1828022Y898951D01*
X1827855Y898701D01*
X1827813Y898410D01*
X1827855Y898160D01*
X1828022Y897910D01*
X1828272Y897701D01*
X1828563Y897618D01*
X1828897Y897701D01*
X1829188Y897951D01*
X1829355Y898326D01*
X1829397Y898743D01*
X1829313Y899285D01*
X1829188Y899576D01*
X1828980Y899868D01*
X1828688Y900076D01*
X1828397Y900118D01*
X1828105Y900035D01*
X1827897Y899826D01*
G01X1826422Y897993D02*
X1826172Y897785D01*
X1825880Y897660D01*
X1825505Y897618D01*
X1825130Y897701D01*
X1824838Y897868D01*
X1824630Y898160D01*
X1824588Y898493D01*
X1824672Y898826D01*
X1824880Y899035D01*
X1825172Y899201D01*
X1825463Y899243D01*
X1825755Y899201D01*
X1826130Y899035D01*
X1826005Y900118D01*
X1824880D01*
G01X1823197Y898660D02*
X1822905Y898951D01*
X1822655Y899118D01*
X1822322Y899201D01*
X1822030Y899118D01*
X1821822Y898951D01*
X1821655Y898701D01*
X1821613Y898410D01*
X1821655Y898160D01*
X1821822Y897910D01*
X1822072Y897701D01*
X1822363Y897618D01*
X1822697Y897701D01*
X1822988Y897951D01*
X1823155Y898326D01*
X1823197Y898743D01*
X1823113Y899285D01*
X1822988Y899576D01*
X1822780Y899868D01*
X1822488Y900076D01*
X1822197Y900118D01*
X1821905Y900035D01*
X1821697Y899826D01*
G01X1824200Y980900D02*
Y992100D01*
G01X1842200Y980900D02*
X1824200D01*
G01X1842200Y992100D02*
Y980900D01*
G01Y980200D02*
Y969000D01*
G01X1824200Y980200D02*
X1842200D01*
G01X1824200Y969000D02*
Y980200D01*
G01X1842200Y941800D02*
Y953000D01*
G01X1824200Y941800D02*
X1842200D01*
G01X1824200Y953000D02*
Y941800D01*
G01X1861557Y970508D02*
Y968008D01*
X1859891D01*
G01X1857707D02*
X1857624Y968550D01*
X1857499Y969008D01*
X1857332Y969425D01*
X1857124Y969883D01*
X1856791Y970508D01*
X1858457D01*
G01X1865700Y954900D02*
X1852300D01*
G01Y962100D02*
X1865700D01*
G01X1852300Y954900D02*
Y962100D01*
G01X1865943Y971813D02*
Y974313D01*
X1864902D01*
X1864568Y974188D01*
X1864360Y974021D01*
X1864277Y973688D01*
X1864360Y973355D01*
X1864610Y973146D01*
X1864902Y973021D01*
X1865943D01*
G01X1864902D02*
X1864277Y971813D01*
G01X1862010D02*
Y974313D01*
X1862510Y973813D01*
G01Y971813D02*
X1861510D01*
G01X1859702Y973896D02*
X1859452Y974146D01*
X1859160Y974271D01*
X1858827Y974313D01*
X1858410Y974230D01*
X1858118Y974021D01*
X1858035Y973771D01*
X1858077Y973521D01*
X1858243Y973313D01*
X1859077Y972896D01*
X1859452Y972605D01*
X1859702Y972188D01*
X1859785Y971813D01*
X1858035D01*
G01X1856602Y972855D02*
X1856310Y973146D01*
X1856060Y973313D01*
X1855727Y973396D01*
X1855435Y973313D01*
X1855227Y973146D01*
X1855060Y972896D01*
X1855018Y972605D01*
X1855060Y972355D01*
X1855227Y972105D01*
X1855477Y971896D01*
X1855768Y971813D01*
X1856102Y971896D01*
X1856393Y972146D01*
X1856560Y972521D01*
X1856602Y972938D01*
X1856518Y973480D01*
X1856393Y973771D01*
X1856185Y974063D01*
X1855893Y974271D01*
X1855602Y974313D01*
X1855310Y974230D01*
X1855102Y974021D01*
G01X1852210Y971813D02*
Y974313D01*
X1853752Y972521D01*
X1851668D01*
G01X1836600Y1027000D02*
Y1024500D01*
G01X1837558Y1027000D02*
X1835642D01*
G01X1832583Y1026792D02*
X1832833Y1026917D01*
X1833125Y1027000D01*
X1833458D01*
X1833833Y1026875D01*
X1834125Y1026667D01*
X1834333Y1026417D01*
X1834500Y1026000D01*
X1834542Y1025625D01*
X1834458Y1025250D01*
X1834333Y1025000D01*
X1834083Y1024750D01*
X1833792Y1024583D01*
X1833500Y1024500D01*
X1833208D01*
X1832917Y1024583D01*
X1832667Y1024708D01*
X1832458Y1024875D01*
G01X1830483Y1024500D02*
X1830400Y1025042D01*
X1830275Y1025500D01*
X1830108Y1025917D01*
X1829900Y1026375D01*
X1829567Y1027000D01*
X1831233D01*
G01X1824200Y1019300D02*
Y1008100D01*
G01X1842200Y1019300D02*
X1824200D01*
G01X1842200Y1008100D02*
Y1019300D01*
G01X1850992Y1007567D02*
X1851117Y1007317D01*
X1851200Y1007025D01*
Y1006692D01*
X1851075Y1006317D01*
X1850867Y1006025D01*
X1850617Y1005817D01*
X1850200Y1005650D01*
X1849825Y1005608D01*
X1849450Y1005692D01*
X1849200Y1005817D01*
X1848950Y1006067D01*
X1848783Y1006358D01*
X1848700Y1006650D01*
Y1006942D01*
X1848783Y1007233D01*
X1848908Y1007483D01*
X1849075Y1007692D01*
G01X1849742Y1008958D02*
X1850033Y1009250D01*
X1850200Y1009500D01*
X1850283Y1009833D01*
X1850200Y1010125D01*
X1850033Y1010333D01*
X1849783Y1010500D01*
X1849492Y1010542D01*
X1849242Y1010500D01*
X1848992Y1010333D01*
X1848783Y1010083D01*
X1848700Y1009792D01*
X1848783Y1009458D01*
X1849033Y1009167D01*
X1849408Y1009000D01*
X1849825Y1008958D01*
X1850367Y1009042D01*
X1850658Y1009167D01*
X1850950Y1009375D01*
X1851158Y1009667D01*
X1851200Y1009958D01*
X1851117Y1010250D01*
X1850908Y1010458D01*
G01X1848700Y1013350D02*
X1851200D01*
X1849408Y1011808D01*
Y1013892D01*
G01X1848700Y1015867D02*
X1849242Y1015950D01*
X1849700Y1016075D01*
X1850117Y1016242D01*
X1850575Y1016450D01*
X1851200Y1016783D01*
Y1015117D01*
G01X1858792Y1007567D02*
X1858917Y1007317D01*
X1859000Y1007025D01*
Y1006692D01*
X1858875Y1006317D01*
X1858667Y1006025D01*
X1858417Y1005817D01*
X1858000Y1005650D01*
X1857625Y1005608D01*
X1857250Y1005692D01*
X1857000Y1005817D01*
X1856750Y1006067D01*
X1856583Y1006358D01*
X1856500Y1006650D01*
Y1006942D01*
X1856583Y1007233D01*
X1856708Y1007483D01*
X1856875Y1007692D01*
G01X1857542Y1008958D02*
X1857833Y1009250D01*
X1858000Y1009500D01*
X1858083Y1009833D01*
X1858000Y1010125D01*
X1857833Y1010333D01*
X1857583Y1010500D01*
X1857292Y1010542D01*
X1857042Y1010500D01*
X1856792Y1010333D01*
X1856583Y1010083D01*
X1856500Y1009792D01*
X1856583Y1009458D01*
X1856833Y1009167D01*
X1857208Y1009000D01*
X1857625Y1008958D01*
X1858167Y1009042D01*
X1858458Y1009167D01*
X1858750Y1009375D01*
X1858958Y1009667D01*
X1859000Y1009958D01*
X1858917Y1010250D01*
X1858708Y1010458D01*
G01X1856500Y1013350D02*
X1859000D01*
X1857208Y1011808D01*
Y1013892D01*
G01X1857542Y1015158D02*
X1857833Y1015450D01*
X1858000Y1015700D01*
X1858083Y1016033D01*
X1858000Y1016325D01*
X1857833Y1016533D01*
X1857583Y1016700D01*
X1857292Y1016742D01*
X1857042Y1016700D01*
X1856792Y1016533D01*
X1856583Y1016283D01*
X1856500Y1015992D01*
X1856583Y1015658D01*
X1856833Y1015367D01*
X1857208Y1015200D01*
X1857625Y1015158D01*
X1858167Y1015242D01*
X1858458Y1015367D01*
X1858750Y1015575D01*
X1858958Y1015867D01*
X1859000Y1016158D01*
X1858917Y1016450D01*
X1858708Y1016658D01*
G01X1873993Y830032D02*
Y848032D01*
G01X1885193Y830032D02*
X1873993D01*
G01X1901193D02*
X1912393D01*
G01X1873293D02*
X1862093D01*
G01X1873293Y848032D02*
Y830032D01*
G01X1894362Y819563D02*
Y822063D01*
X1892446Y819563D01*
Y822063D01*
G01X1891221D02*
Y820271D01*
X1891054Y819896D01*
X1890721Y819646D01*
X1890304Y819563D01*
X1889887Y819646D01*
X1889554Y819896D01*
X1889387Y820271D01*
Y822063D01*
G01X1887204D02*
Y819563D01*
G01X1888162Y822063D02*
X1886246D01*
G01X1884896Y821646D02*
X1884646Y821896D01*
X1884354Y822021D01*
X1884021Y822063D01*
X1883604Y821980D01*
X1883312Y821771D01*
X1883229Y821521D01*
X1883271Y821271D01*
X1883437Y821063D01*
X1884271Y820646D01*
X1884646Y820355D01*
X1884896Y819938D01*
X1884979Y819563D01*
X1883229D01*
G01X1886000Y892700D02*
X1890000D01*
Y885300D01*
G01X1893933Y866435D02*
Y868935D01*
X1892892D01*
X1892558Y868810D01*
X1892350Y868643D01*
X1892267Y868310D01*
X1892350Y867977D01*
X1892600Y867768D01*
X1892892Y867643D01*
X1893933D01*
G01X1892892D02*
X1892267Y866435D01*
G01X1890000D02*
Y868935D01*
X1890500Y868435D01*
G01Y866435D02*
X1889500D01*
G01X1887692Y868518D02*
X1887442Y868768D01*
X1887150Y868893D01*
X1886817Y868935D01*
X1886400Y868852D01*
X1886108Y868643D01*
X1886025Y868393D01*
X1886067Y868143D01*
X1886233Y867935D01*
X1887067Y867518D01*
X1887442Y867227D01*
X1887692Y866810D01*
X1887775Y866435D01*
X1886025D01*
G01X1884592Y867477D02*
X1884300Y867768D01*
X1884050Y867935D01*
X1883717Y868018D01*
X1883425Y867935D01*
X1883217Y867768D01*
X1883050Y867518D01*
X1883008Y867227D01*
X1883050Y866977D01*
X1883217Y866727D01*
X1883467Y866518D01*
X1883758Y866435D01*
X1884092Y866518D01*
X1884383Y866768D01*
X1884550Y867143D01*
X1884592Y867560D01*
X1884508Y868102D01*
X1884383Y868393D01*
X1884175Y868685D01*
X1883883Y868893D01*
X1883592Y868935D01*
X1883300Y868852D01*
X1883092Y868643D01*
G01X1880700Y866435D02*
X1880408Y866477D01*
X1880075Y866602D01*
X1879867Y866810D01*
X1879783Y867102D01*
X1879867Y867393D01*
X1880117Y867643D01*
X1880492Y867768D01*
X1880908D01*
X1881158Y867852D01*
X1881367Y868060D01*
X1881450Y868352D01*
X1881325Y868643D01*
X1881033Y868852D01*
X1880700Y868935D01*
X1880367Y868852D01*
X1880075Y868643D01*
X1879950Y868352D01*
X1880033Y868060D01*
X1880242Y867852D01*
X1880492Y867768D01*
X1880908D01*
X1881283Y867643D01*
X1881533Y867393D01*
X1881617Y867102D01*
X1881533Y866810D01*
X1881325Y866602D01*
X1880992Y866477D01*
X1880700Y866435D01*
G01X1881050Y878323D02*
Y882323D01*
X1888450D01*
G01X1894500Y885300D02*
X1890500D01*
Y892700D01*
G01X1908500Y884800D02*
X1904500D01*
Y892200D01*
G01X1873993Y848032D02*
X1885193D01*
G01X1912393D02*
X1901193D01*
G01X1862093D02*
X1873293D01*
G01X1892183Y865027D02*
X1892433Y865152D01*
X1892725Y865235D01*
X1893058D01*
X1893433Y865110D01*
X1893725Y864902D01*
X1893933Y864652D01*
X1894100Y864235D01*
X1894142Y863860D01*
X1894058Y863485D01*
X1893933Y863235D01*
X1893683Y862985D01*
X1893392Y862818D01*
X1893100Y862735D01*
X1892808D01*
X1892517Y862818D01*
X1892267Y862943D01*
X1892058Y863110D01*
G01X1890792Y863777D02*
X1890500Y864068D01*
X1890250Y864235D01*
X1889917Y864318D01*
X1889625Y864235D01*
X1889417Y864068D01*
X1889250Y863818D01*
X1889208Y863527D01*
X1889250Y863277D01*
X1889417Y863027D01*
X1889667Y862818D01*
X1889958Y862735D01*
X1890292Y862818D01*
X1890583Y863068D01*
X1890750Y863443D01*
X1890792Y863860D01*
X1890708Y864402D01*
X1890583Y864693D01*
X1890375Y864985D01*
X1890083Y865193D01*
X1889792Y865235D01*
X1889500Y865152D01*
X1889292Y864943D01*
G01X1887817Y863110D02*
X1887567Y862902D01*
X1887275Y862777D01*
X1886900Y862735D01*
X1886525Y862818D01*
X1886233Y862985D01*
X1886025Y863277D01*
X1885983Y863610D01*
X1886067Y863943D01*
X1886275Y864152D01*
X1886567Y864318D01*
X1886858Y864360D01*
X1887150Y864318D01*
X1887525Y864152D01*
X1887400Y865235D01*
X1886275D01*
G01X1883800Y862735D02*
X1883508Y862777D01*
X1883175Y862902D01*
X1882967Y863110D01*
X1882883Y863402D01*
X1882967Y863693D01*
X1883217Y863943D01*
X1883592Y864068D01*
X1884008D01*
X1884258Y864152D01*
X1884467Y864360D01*
X1884550Y864652D01*
X1884425Y864943D01*
X1884133Y865152D01*
X1883800Y865235D01*
X1883467Y865152D01*
X1883175Y864943D01*
X1883050Y864652D01*
X1883133Y864360D01*
X1883342Y864152D01*
X1883592Y864068D01*
X1884008D01*
X1884383Y863943D01*
X1884633Y863693D01*
X1884717Y863402D01*
X1884633Y863110D01*
X1884425Y862902D01*
X1884092Y862777D01*
X1883800Y862735D01*
G01X1898278Y864058D02*
X1898403Y863808D01*
X1898486Y863516D01*
Y863183D01*
X1898361Y862808D01*
X1898153Y862516D01*
X1897903Y862308D01*
X1897486Y862141D01*
X1897111Y862099D01*
X1896736Y862183D01*
X1896486Y862308D01*
X1896236Y862558D01*
X1896069Y862849D01*
X1895986Y863141D01*
Y863433D01*
X1896069Y863724D01*
X1896194Y863974D01*
X1896361Y864183D01*
G01X1897028Y865449D02*
X1897319Y865741D01*
X1897486Y865991D01*
X1897569Y866324D01*
X1897486Y866616D01*
X1897319Y866824D01*
X1897069Y866991D01*
X1896778Y867033D01*
X1896528Y866991D01*
X1896278Y866824D01*
X1896069Y866574D01*
X1895986Y866283D01*
X1896069Y865949D01*
X1896319Y865658D01*
X1896694Y865491D01*
X1897111Y865449D01*
X1897653Y865533D01*
X1897944Y865658D01*
X1898236Y865866D01*
X1898444Y866158D01*
X1898486Y866449D01*
X1898403Y866741D01*
X1898194Y866949D01*
G01X1897028Y868549D02*
X1897319Y868841D01*
X1897486Y869091D01*
X1897569Y869424D01*
X1897486Y869716D01*
X1897319Y869924D01*
X1897069Y870091D01*
X1896778Y870133D01*
X1896528Y870091D01*
X1896278Y869924D01*
X1896069Y869674D01*
X1895986Y869383D01*
X1896069Y869049D01*
X1896319Y868758D01*
X1896694Y868591D01*
X1897111Y868549D01*
X1897653Y868633D01*
X1897944Y868758D01*
X1898236Y868966D01*
X1898444Y869258D01*
X1898486Y869549D01*
X1898403Y869841D01*
X1898194Y870049D01*
G01X1898486Y872441D02*
X1898403Y872108D01*
X1898194Y871858D01*
X1897944Y871691D01*
X1897611Y871566D01*
X1897236Y871524D01*
X1896861Y871566D01*
X1896528Y871691D01*
X1896278Y871858D01*
X1896069Y872108D01*
X1895986Y872441D01*
X1896069Y872774D01*
X1896278Y873024D01*
X1896528Y873191D01*
X1896861Y873316D01*
X1897236Y873358D01*
X1897611Y873316D01*
X1897944Y873191D01*
X1898194Y873024D01*
X1898403Y872774D01*
X1898486Y872441D01*
G01X1887500Y911200D02*
X1891500D01*
Y903800D01*
G01X1898943Y895550D02*
X1894943D01*
Y902950D01*
G01X1907943Y895550D02*
X1903943D01*
Y902950D01*
G01X1890443D02*
X1894443D01*
Y895550D01*
G01X1894800Y936000D02*
Y940000D01*
X1902200D01*
G01Y935500D02*
Y931500D01*
X1894800D01*
G01X1902200Y931000D02*
Y927000D01*
X1894800D01*
G01Y919000D02*
Y923000D01*
X1902200D01*
G01X1894800D02*
Y927000D01*
X1902200D01*
G01X1908832Y912665D02*
X1911332D01*
Y913706D01*
X1911207Y914040D01*
X1911040Y914248D01*
X1910707Y914331D01*
X1910374Y914248D01*
X1910165Y913998D01*
X1910040Y913706D01*
Y912665D01*
G01Y913706D02*
X1908832Y914331D01*
G01Y916598D02*
X1911332D01*
X1910832Y916098D01*
G01X1908832D02*
Y917098D01*
G01X1910915Y918906D02*
X1911165Y919156D01*
X1911290Y919448D01*
X1911332Y919781D01*
X1911249Y920198D01*
X1911040Y920490D01*
X1910790Y920573D01*
X1910540Y920531D01*
X1910332Y920365D01*
X1909915Y919531D01*
X1909624Y919156D01*
X1909207Y918906D01*
X1908832Y918823D01*
Y920573D01*
G01Y922798D02*
X1908874Y923090D01*
X1908999Y923423D01*
X1909207Y923631D01*
X1909499Y923715D01*
X1909790Y923631D01*
X1910040Y923381D01*
X1910165Y923006D01*
Y922590D01*
X1910249Y922340D01*
X1910457Y922131D01*
X1910749Y922048D01*
X1911040Y922173D01*
X1911249Y922465D01*
X1911332Y922798D01*
X1911249Y923131D01*
X1911040Y923423D01*
X1910749Y923548D01*
X1910457Y923465D01*
X1910249Y923256D01*
X1910165Y923006D01*
Y922590D01*
X1910040Y922215D01*
X1909790Y921965D01*
X1909499Y921881D01*
X1909207Y921965D01*
X1908999Y922173D01*
X1908874Y922506D01*
X1908832Y922798D01*
G01X1911332Y925898D02*
X1911249Y925565D01*
X1911040Y925315D01*
X1910790Y925148D01*
X1910457Y925023D01*
X1910082Y924981D01*
X1909707Y925023D01*
X1909374Y925148D01*
X1909124Y925315D01*
X1908915Y925565D01*
X1908832Y925898D01*
X1908915Y926231D01*
X1909124Y926481D01*
X1909374Y926648D01*
X1909707Y926773D01*
X1910082Y926815D01*
X1910457Y926773D01*
X1910790Y926648D01*
X1911040Y926481D01*
X1911249Y926231D01*
X1911332Y925898D01*
G01X1886500Y903800D02*
X1882500D01*
Y911200D01*
G01X1877276Y929909D02*
X1882276D01*
Y924909D01*
G01X1874182Y928902D02*
Y931902D01*
G01X1864339Y928902D02*
Y930902D01*
G01X1870245Y903216D02*
Y901216D01*
G01X1907001Y915677D02*
Y918177D01*
X1906001D01*
X1905668Y918052D01*
X1905418Y917760D01*
X1905335Y917427D01*
X1905418Y917094D01*
X1905626Y916844D01*
X1906001Y916719D01*
X1907001D01*
G01X1902818Y916927D02*
X1901985D01*
Y916177D01*
X1902235Y915927D01*
X1902526Y915760D01*
X1902943Y915677D01*
X1903360Y915760D01*
X1903651Y915927D01*
X1903901Y916177D01*
X1904068Y916469D01*
X1904151Y916802D01*
Y917094D01*
X1904068Y917344D01*
X1903901Y917635D01*
X1903651Y917885D01*
X1903401Y918052D01*
X1903068Y918177D01*
X1902776D01*
X1902443Y918094D01*
X1902193Y917927D01*
G01X1899968Y915677D02*
Y918177D01*
X1900468Y917677D01*
G01Y915677D02*
X1899468D01*
G01X1896951D02*
X1896868Y916219D01*
X1896743Y916677D01*
X1896576Y917094D01*
X1896368Y917552D01*
X1896035Y918177D01*
X1897701D01*
G01X1909286Y956356D02*
Y958856D01*
X1908245D01*
X1907911Y958731D01*
X1907703Y958564D01*
X1907620Y958231D01*
X1907703Y957898D01*
X1907953Y957689D01*
X1908245Y957564D01*
X1909286D01*
G01X1908245D02*
X1907620Y956356D01*
G01X1905353D02*
Y958856D01*
X1905853Y958356D01*
G01Y956356D02*
X1904853D01*
G01X1903045Y958439D02*
X1902795Y958689D01*
X1902503Y958814D01*
X1902170Y958856D01*
X1901753Y958773D01*
X1901461Y958564D01*
X1901378Y958314D01*
X1901420Y958064D01*
X1901586Y957856D01*
X1902420Y957439D01*
X1902795Y957148D01*
X1903045Y956731D01*
X1903128Y956356D01*
X1901378D01*
G01X1899236D02*
X1899153Y956898D01*
X1899028Y957356D01*
X1898861Y957773D01*
X1898653Y958231D01*
X1898320Y958856D01*
X1899986D01*
G01X1896053D02*
X1896386Y958773D01*
X1896636Y958564D01*
X1896803Y958314D01*
X1896928Y957981D01*
X1896970Y957606D01*
X1896928Y957231D01*
X1896803Y956898D01*
X1896636Y956648D01*
X1896386Y956439D01*
X1896053Y956356D01*
X1895720Y956439D01*
X1895470Y956648D01*
X1895303Y956898D01*
X1895178Y957231D01*
X1895136Y957606D01*
X1895178Y957981D01*
X1895303Y958314D01*
X1895470Y958564D01*
X1895720Y958773D01*
X1896053Y958856D01*
G01X1909286Y952656D02*
Y955156D01*
X1908245D01*
X1907911Y955031D01*
X1907703Y954864D01*
X1907620Y954531D01*
X1907703Y954198D01*
X1907953Y953989D01*
X1908245Y953864D01*
X1909286D01*
G01X1908245D02*
X1907620Y952656D01*
G01X1905353D02*
Y955156D01*
X1905853Y954656D01*
G01Y952656D02*
X1904853D01*
G01X1903045Y954739D02*
X1902795Y954989D01*
X1902503Y955114D01*
X1902170Y955156D01*
X1901753Y955073D01*
X1901461Y954864D01*
X1901378Y954614D01*
X1901420Y954364D01*
X1901586Y954156D01*
X1902420Y953739D01*
X1902795Y953448D01*
X1903045Y953031D01*
X1903128Y952656D01*
X1901378D01*
G01X1899236D02*
X1899153Y953198D01*
X1899028Y953656D01*
X1898861Y954073D01*
X1898653Y954531D01*
X1898320Y955156D01*
X1899986D01*
G01X1896845Y954739D02*
X1896595Y954989D01*
X1896303Y955114D01*
X1895970Y955156D01*
X1895553Y955073D01*
X1895261Y954864D01*
X1895178Y954614D01*
X1895220Y954364D01*
X1895386Y954156D01*
X1896220Y953739D01*
X1896595Y953448D01*
X1896845Y953031D01*
X1896928Y952656D01*
X1895178D01*
G01X1909286Y948956D02*
Y951456D01*
X1908245D01*
X1907911Y951331D01*
X1907703Y951164D01*
X1907620Y950831D01*
X1907703Y950498D01*
X1907953Y950289D01*
X1908245Y950164D01*
X1909286D01*
G01X1908245D02*
X1907620Y948956D01*
G01X1905353D02*
Y951456D01*
X1905853Y950956D01*
G01Y948956D02*
X1904853D01*
G01X1903045Y951039D02*
X1902795Y951289D01*
X1902503Y951414D01*
X1902170Y951456D01*
X1901753Y951373D01*
X1901461Y951164D01*
X1901378Y950914D01*
X1901420Y950664D01*
X1901586Y950456D01*
X1902420Y950039D01*
X1902795Y949748D01*
X1903045Y949331D01*
X1903128Y948956D01*
X1901378D01*
G01X1899236D02*
X1899153Y949498D01*
X1899028Y949956D01*
X1898861Y950373D01*
X1898653Y950831D01*
X1898320Y951456D01*
X1899986D01*
G01X1896970Y949331D02*
X1896720Y949123D01*
X1896428Y948998D01*
X1896053Y948956D01*
X1895678Y949039D01*
X1895386Y949206D01*
X1895178Y949498D01*
X1895136Y949831D01*
X1895220Y950164D01*
X1895428Y950373D01*
X1895720Y950539D01*
X1896011Y950581D01*
X1896303Y950539D01*
X1896678Y950373D01*
X1896553Y951456D01*
X1895428D01*
G01X1909286Y941556D02*
Y944056D01*
X1908245D01*
X1907911Y943931D01*
X1907703Y943764D01*
X1907620Y943431D01*
X1907703Y943098D01*
X1907953Y942889D01*
X1908245Y942764D01*
X1909286D01*
G01X1908245D02*
X1907620Y941556D01*
G01X1905353D02*
Y944056D01*
X1905853Y943556D01*
G01Y941556D02*
X1904853D01*
G01X1903045Y943639D02*
X1902795Y943889D01*
X1902503Y944014D01*
X1902170Y944056D01*
X1901753Y943973D01*
X1901461Y943764D01*
X1901378Y943514D01*
X1901420Y943264D01*
X1901586Y943056D01*
X1902420Y942639D01*
X1902795Y942348D01*
X1903045Y941931D01*
X1903128Y941556D01*
X1901378D01*
G01X1899236D02*
X1899153Y942098D01*
X1899028Y942556D01*
X1898861Y942973D01*
X1898653Y943431D01*
X1898320Y944056D01*
X1899986D01*
G01X1896845Y942598D02*
X1896553Y942889D01*
X1896303Y943056D01*
X1895970Y943139D01*
X1895678Y943056D01*
X1895470Y942889D01*
X1895303Y942639D01*
X1895261Y942348D01*
X1895303Y942098D01*
X1895470Y941848D01*
X1895720Y941639D01*
X1896011Y941556D01*
X1896345Y941639D01*
X1896636Y941889D01*
X1896803Y942264D01*
X1896845Y942681D01*
X1896761Y943223D01*
X1896636Y943514D01*
X1896428Y943806D01*
X1896136Y944014D01*
X1895845Y944056D01*
X1895553Y943973D01*
X1895345Y943764D01*
G01X1909286Y945256D02*
Y947756D01*
X1908245D01*
X1907911Y947631D01*
X1907703Y947464D01*
X1907620Y947131D01*
X1907703Y946798D01*
X1907953Y946589D01*
X1908245Y946464D01*
X1909286D01*
G01X1908245D02*
X1907620Y945256D01*
G01X1905353D02*
Y947756D01*
X1905853Y947256D01*
G01Y945256D02*
X1904853D01*
G01X1903045Y947339D02*
X1902795Y947589D01*
X1902503Y947714D01*
X1902170Y947756D01*
X1901753Y947673D01*
X1901461Y947464D01*
X1901378Y947214D01*
X1901420Y946964D01*
X1901586Y946756D01*
X1902420Y946339D01*
X1902795Y946048D01*
X1903045Y945631D01*
X1903128Y945256D01*
X1901378D01*
G01X1899236D02*
X1899153Y945798D01*
X1899028Y946256D01*
X1898861Y946673D01*
X1898653Y947131D01*
X1898320Y947756D01*
X1899986D01*
G01X1896053Y945256D02*
X1895761Y945298D01*
X1895428Y945423D01*
X1895220Y945631D01*
X1895136Y945923D01*
X1895220Y946214D01*
X1895470Y946464D01*
X1895845Y946589D01*
X1896261D01*
X1896511Y946673D01*
X1896720Y946881D01*
X1896803Y947173D01*
X1896678Y947464D01*
X1896386Y947673D01*
X1896053Y947756D01*
X1895720Y947673D01*
X1895428Y947464D01*
X1895303Y947173D01*
X1895386Y946881D01*
X1895595Y946673D01*
X1895845Y946589D01*
X1896261D01*
X1896636Y946464D01*
X1896886Y946214D01*
X1896970Y945923D01*
X1896886Y945631D01*
X1896678Y945423D01*
X1896345Y945298D01*
X1896053Y945256D01*
G01X1865700Y962100D02*
Y954900D01*
G01X1886835Y958158D02*
X1886960Y957908D01*
X1887043Y957616D01*
Y957283D01*
X1886918Y956908D01*
X1886710Y956616D01*
X1886460Y956408D01*
X1886043Y956241D01*
X1885668Y956199D01*
X1885293Y956283D01*
X1885043Y956408D01*
X1884793Y956658D01*
X1884626Y956949D01*
X1884543Y957241D01*
Y957533D01*
X1884626Y957824D01*
X1884751Y958074D01*
X1884918Y958283D01*
G01X1885585Y959549D02*
X1885876Y959841D01*
X1886043Y960091D01*
X1886126Y960424D01*
X1886043Y960716D01*
X1885876Y960924D01*
X1885626Y961091D01*
X1885335Y961133D01*
X1885085Y961091D01*
X1884835Y960924D01*
X1884626Y960674D01*
X1884543Y960383D01*
X1884626Y960049D01*
X1884876Y959758D01*
X1885251Y959591D01*
X1885668Y959549D01*
X1886210Y959633D01*
X1886501Y959758D01*
X1886793Y959966D01*
X1887001Y960258D01*
X1887043Y960549D01*
X1886960Y960841D01*
X1886751Y961049D01*
G01X1884918Y962524D02*
X1884710Y962774D01*
X1884585Y963066D01*
X1884543Y963441D01*
X1884626Y963816D01*
X1884793Y964108D01*
X1885085Y964316D01*
X1885418Y964358D01*
X1885751Y964274D01*
X1885960Y964066D01*
X1886126Y963774D01*
X1886168Y963483D01*
X1886126Y963191D01*
X1885960Y962816D01*
X1887043Y962941D01*
Y964066D01*
G01X1884918Y965624D02*
X1884710Y965874D01*
X1884585Y966166D01*
X1884543Y966541D01*
X1884626Y966916D01*
X1884793Y967208D01*
X1885085Y967416D01*
X1885418Y967458D01*
X1885751Y967374D01*
X1885960Y967166D01*
X1886126Y966874D01*
X1886168Y966583D01*
X1886126Y966291D01*
X1885960Y965916D01*
X1887043Y966041D01*
Y967166D01*
G01X1877368Y962050D02*
X1877618Y962175D01*
X1877910Y962258D01*
X1878243D01*
X1878618Y962133D01*
X1878910Y961925D01*
X1879118Y961675D01*
X1879285Y961258D01*
X1879327Y960883D01*
X1879243Y960508D01*
X1879118Y960258D01*
X1878868Y960008D01*
X1878577Y959841D01*
X1878285Y959758D01*
X1877993D01*
X1877702Y959841D01*
X1877452Y959966D01*
X1877243Y960133D01*
G01X1875977Y960800D02*
X1875685Y961091D01*
X1875435Y961258D01*
X1875102Y961341D01*
X1874810Y961258D01*
X1874602Y961091D01*
X1874435Y960841D01*
X1874393Y960550D01*
X1874435Y960300D01*
X1874602Y960050D01*
X1874852Y959841D01*
X1875143Y959758D01*
X1875477Y959841D01*
X1875768Y960091D01*
X1875935Y960466D01*
X1875977Y960883D01*
X1875893Y961425D01*
X1875768Y961716D01*
X1875560Y962008D01*
X1875268Y962216D01*
X1874977Y962258D01*
X1874685Y962175D01*
X1874477Y961966D01*
G01X1873002Y960133D02*
X1872752Y959925D01*
X1872460Y959800D01*
X1872085Y959758D01*
X1871710Y959841D01*
X1871418Y960008D01*
X1871210Y960300D01*
X1871168Y960633D01*
X1871252Y960966D01*
X1871460Y961175D01*
X1871752Y961341D01*
X1872043Y961383D01*
X1872335Y961341D01*
X1872710Y961175D01*
X1872585Y962258D01*
X1871460D01*
G01X1868985D02*
X1869318Y962175D01*
X1869568Y961966D01*
X1869735Y961716D01*
X1869860Y961383D01*
X1869902Y961008D01*
X1869860Y960633D01*
X1869735Y960300D01*
X1869568Y960050D01*
X1869318Y959841D01*
X1868985Y959758D01*
X1868652Y959841D01*
X1868402Y960050D01*
X1868235Y960300D01*
X1868110Y960633D01*
X1868068Y961008D01*
X1868110Y961383D01*
X1868235Y961716D01*
X1868402Y961966D01*
X1868652Y962175D01*
X1868985Y962258D01*
G01X1877368Y965750D02*
X1877618Y965875D01*
X1877910Y965958D01*
X1878243D01*
X1878618Y965833D01*
X1878910Y965625D01*
X1879118Y965375D01*
X1879285Y964958D01*
X1879327Y964583D01*
X1879243Y964208D01*
X1879118Y963958D01*
X1878868Y963708D01*
X1878577Y963541D01*
X1878285Y963458D01*
X1877993D01*
X1877702Y963541D01*
X1877452Y963666D01*
X1877243Y963833D01*
G01X1875977Y964500D02*
X1875685Y964791D01*
X1875435Y964958D01*
X1875102Y965041D01*
X1874810Y964958D01*
X1874602Y964791D01*
X1874435Y964541D01*
X1874393Y964250D01*
X1874435Y964000D01*
X1874602Y963750D01*
X1874852Y963541D01*
X1875143Y963458D01*
X1875477Y963541D01*
X1875768Y963791D01*
X1875935Y964166D01*
X1875977Y964583D01*
X1875893Y965125D01*
X1875768Y965416D01*
X1875560Y965708D01*
X1875268Y965916D01*
X1874977Y965958D01*
X1874685Y965875D01*
X1874477Y965666D01*
G01X1871585Y963458D02*
Y965958D01*
X1873127Y964166D01*
X1871043D01*
G01X1869693Y963750D02*
X1869402Y963541D01*
X1869068Y963458D01*
X1868735Y963541D01*
X1868443Y963791D01*
X1868235Y964166D01*
X1868152Y964541D01*
Y965000D01*
X1868235Y965375D01*
X1868443Y965708D01*
X1868693Y965875D01*
X1868985Y965958D01*
X1869318Y965875D01*
X1869568Y965708D01*
X1869735Y965458D01*
X1869818Y965125D01*
X1869735Y964833D01*
X1869527Y964541D01*
X1869277Y964375D01*
X1868985Y964333D01*
X1868652Y964416D01*
X1868402Y964625D01*
X1868152Y965000D01*
G01X1883135Y958158D02*
X1883260Y957908D01*
X1883343Y957616D01*
Y957283D01*
X1883218Y956908D01*
X1883010Y956616D01*
X1882760Y956408D01*
X1882343Y956241D01*
X1881968Y956199D01*
X1881593Y956283D01*
X1881343Y956408D01*
X1881093Y956658D01*
X1880926Y956949D01*
X1880843Y957241D01*
Y957533D01*
X1880926Y957824D01*
X1881051Y958074D01*
X1881218Y958283D01*
G01X1881885Y959549D02*
X1882176Y959841D01*
X1882343Y960091D01*
X1882426Y960424D01*
X1882343Y960716D01*
X1882176Y960924D01*
X1881926Y961091D01*
X1881635Y961133D01*
X1881385Y961091D01*
X1881135Y960924D01*
X1880926Y960674D01*
X1880843Y960383D01*
X1880926Y960049D01*
X1881176Y959758D01*
X1881551Y959591D01*
X1881968Y959549D01*
X1882510Y959633D01*
X1882801Y959758D01*
X1883093Y959966D01*
X1883301Y960258D01*
X1883343Y960549D01*
X1883260Y960841D01*
X1883051Y961049D01*
G01X1881218Y962524D02*
X1881010Y962774D01*
X1880885Y963066D01*
X1880843Y963441D01*
X1880926Y963816D01*
X1881093Y964108D01*
X1881385Y964316D01*
X1881718Y964358D01*
X1882051Y964274D01*
X1882260Y964066D01*
X1882426Y963774D01*
X1882468Y963483D01*
X1882426Y963191D01*
X1882260Y962816D01*
X1883343Y962941D01*
Y964066D01*
G01X1881135Y965833D02*
X1880926Y966124D01*
X1880843Y966458D01*
X1880926Y966791D01*
X1881176Y967083D01*
X1881551Y967291D01*
X1881926Y967374D01*
X1882385D01*
X1882760Y967291D01*
X1883093Y967083D01*
X1883260Y966833D01*
X1883343Y966541D01*
X1883260Y966208D01*
X1883093Y965958D01*
X1882843Y965791D01*
X1882510Y965708D01*
X1882218Y965791D01*
X1881926Y965999D01*
X1881760Y966249D01*
X1881718Y966541D01*
X1881801Y966874D01*
X1882010Y967124D01*
X1882385Y967374D01*
G01X1877368Y958350D02*
X1877618Y958475D01*
X1877910Y958558D01*
X1878243D01*
X1878618Y958433D01*
X1878910Y958225D01*
X1879118Y957975D01*
X1879285Y957558D01*
X1879327Y957183D01*
X1879243Y956808D01*
X1879118Y956558D01*
X1878868Y956308D01*
X1878577Y956141D01*
X1878285Y956058D01*
X1877993D01*
X1877702Y956141D01*
X1877452Y956266D01*
X1877243Y956433D01*
G01X1875977Y957100D02*
X1875685Y957391D01*
X1875435Y957558D01*
X1875102Y957641D01*
X1874810Y957558D01*
X1874602Y957391D01*
X1874435Y957141D01*
X1874393Y956850D01*
X1874435Y956600D01*
X1874602Y956350D01*
X1874852Y956141D01*
X1875143Y956058D01*
X1875477Y956141D01*
X1875768Y956391D01*
X1875935Y956766D01*
X1875977Y957183D01*
X1875893Y957725D01*
X1875768Y958016D01*
X1875560Y958308D01*
X1875268Y958516D01*
X1874977Y958558D01*
X1874685Y958475D01*
X1874477Y958266D01*
G01X1873002Y956433D02*
X1872752Y956225D01*
X1872460Y956100D01*
X1872085Y956058D01*
X1871710Y956141D01*
X1871418Y956308D01*
X1871210Y956600D01*
X1871168Y956933D01*
X1871252Y957266D01*
X1871460Y957475D01*
X1871752Y957641D01*
X1872043Y957683D01*
X1872335Y957641D01*
X1872710Y957475D01*
X1872585Y958558D01*
X1871460D01*
G01X1868985Y956058D02*
Y958558D01*
X1869485Y958058D01*
G01Y956058D02*
X1868485D01*
G01X1871000Y987517D02*
X1873500D01*
Y988517D01*
X1873375Y988850D01*
X1873083Y989100D01*
X1872750Y989183D01*
X1872417Y989100D01*
X1872167Y988892D01*
X1872042Y988517D01*
Y987517D01*
G01X1872250Y991700D02*
Y992533D01*
X1871500D01*
X1871250Y992283D01*
X1871083Y991992D01*
X1871000Y991575D01*
X1871083Y991158D01*
X1871250Y990867D01*
X1871500Y990617D01*
X1871792Y990450D01*
X1872125Y990367D01*
X1872417D01*
X1872667Y990450D01*
X1872958Y990617D01*
X1873208Y990867D01*
X1873375Y991117D01*
X1873500Y991450D01*
Y991742D01*
X1873417Y992075D01*
X1873250Y992325D01*
G01X1871000Y994550D02*
X1873500D01*
X1873000Y994050D01*
G01X1871000D02*
Y995050D01*
G01Y998150D02*
X1873500D01*
X1871708Y996608D01*
Y998692D01*
G01X1866592Y1007567D02*
X1866717Y1007317D01*
X1866800Y1007025D01*
Y1006692D01*
X1866675Y1006317D01*
X1866467Y1006025D01*
X1866217Y1005817D01*
X1865800Y1005650D01*
X1865425Y1005608D01*
X1865050Y1005692D01*
X1864800Y1005817D01*
X1864550Y1006067D01*
X1864383Y1006358D01*
X1864300Y1006650D01*
Y1006942D01*
X1864383Y1007233D01*
X1864508Y1007483D01*
X1864675Y1007692D01*
G01X1865342Y1008958D02*
X1865633Y1009250D01*
X1865800Y1009500D01*
X1865883Y1009833D01*
X1865800Y1010125D01*
X1865633Y1010333D01*
X1865383Y1010500D01*
X1865092Y1010542D01*
X1864842Y1010500D01*
X1864592Y1010333D01*
X1864383Y1010083D01*
X1864300Y1009792D01*
X1864383Y1009458D01*
X1864633Y1009167D01*
X1865008Y1009000D01*
X1865425Y1008958D01*
X1865967Y1009042D01*
X1866258Y1009167D01*
X1866550Y1009375D01*
X1866758Y1009667D01*
X1866800Y1009958D01*
X1866717Y1010250D01*
X1866508Y1010458D01*
G01X1864300Y1013350D02*
X1866800D01*
X1865008Y1011808D01*
Y1013892D01*
G01X1864675Y1015033D02*
X1864467Y1015283D01*
X1864342Y1015575D01*
X1864300Y1015950D01*
X1864383Y1016325D01*
X1864550Y1016617D01*
X1864842Y1016825D01*
X1865175Y1016867D01*
X1865508Y1016783D01*
X1865717Y1016575D01*
X1865883Y1016283D01*
X1865925Y1015992D01*
X1865883Y1015700D01*
X1865717Y1015325D01*
X1866800Y1015450D01*
Y1016575D01*
G01X1916994Y835799D02*
X1914494D01*
G01X1916994Y834841D02*
Y836757D01*
G01X1916786Y839816D02*
X1916911Y839566D01*
X1916994Y839274D01*
Y838941D01*
X1916869Y838566D01*
X1916661Y838274D01*
X1916411Y838066D01*
X1915994Y837899D01*
X1915619Y837857D01*
X1915244Y837941D01*
X1914994Y838066D01*
X1914744Y838316D01*
X1914577Y838607D01*
X1914494Y838899D01*
Y839191D01*
X1914577Y839482D01*
X1914702Y839732D01*
X1914869Y839941D01*
G01X1914494Y841999D02*
X1914536Y842291D01*
X1914661Y842624D01*
X1914869Y842832D01*
X1915161Y842916D01*
X1915452Y842832D01*
X1915702Y842582D01*
X1915827Y842207D01*
Y841791D01*
X1915911Y841541D01*
X1916119Y841332D01*
X1916411Y841249D01*
X1916702Y841374D01*
X1916911Y841666D01*
X1916994Y841999D01*
X1916911Y842332D01*
X1916702Y842624D01*
X1916411Y842749D01*
X1916119Y842666D01*
X1915911Y842457D01*
X1915827Y842207D01*
Y841791D01*
X1915702Y841416D01*
X1915452Y841166D01*
X1915161Y841082D01*
X1914869Y841166D01*
X1914661Y841374D01*
X1914536Y841707D01*
X1914494Y841999D01*
G01X1912393Y830032D02*
Y848032D01*
G01X1913010Y874545D02*
X1915510D01*
Y875586D01*
X1915385Y875920D01*
X1915218Y876128D01*
X1914885Y876211D01*
X1914552Y876128D01*
X1914343Y875878D01*
X1914218Y875586D01*
Y874545D01*
G01Y875586D02*
X1913010Y876211D01*
G01Y878478D02*
X1915510D01*
X1915010Y877978D01*
G01X1913010D02*
Y878978D01*
G01X1915093Y880786D02*
X1915343Y881036D01*
X1915468Y881328D01*
X1915510Y881661D01*
X1915427Y882078D01*
X1915218Y882370D01*
X1914968Y882453D01*
X1914718Y882411D01*
X1914510Y882245D01*
X1914093Y881411D01*
X1913802Y881036D01*
X1913385Y880786D01*
X1913010Y880703D01*
Y882453D01*
G01X1914052Y883886D02*
X1914343Y884178D01*
X1914510Y884428D01*
X1914593Y884761D01*
X1914510Y885053D01*
X1914343Y885261D01*
X1914093Y885428D01*
X1913802Y885470D01*
X1913552Y885428D01*
X1913302Y885261D01*
X1913093Y885011D01*
X1913010Y884720D01*
X1913093Y884386D01*
X1913343Y884095D01*
X1913718Y883928D01*
X1914135Y883886D01*
X1914677Y883970D01*
X1914968Y884095D01*
X1915260Y884303D01*
X1915468Y884595D01*
X1915510Y884886D01*
X1915427Y885178D01*
X1915218Y885386D01*
G01X1913010Y887695D02*
X1913552Y887778D01*
X1914010Y887903D01*
X1914427Y888070D01*
X1914885Y888278D01*
X1915510Y888611D01*
Y886945D01*
G01X1916710Y874545D02*
X1919210D01*
Y875586D01*
X1919085Y875920D01*
X1918918Y876128D01*
X1918585Y876211D01*
X1918252Y876128D01*
X1918043Y875878D01*
X1917918Y875586D01*
Y874545D01*
G01Y875586D02*
X1916710Y876211D01*
G01Y878478D02*
X1919210D01*
X1918710Y877978D01*
G01X1916710D02*
Y878978D01*
G01X1918793Y880786D02*
X1919043Y881036D01*
X1919168Y881328D01*
X1919210Y881661D01*
X1919127Y882078D01*
X1918918Y882370D01*
X1918668Y882453D01*
X1918418Y882411D01*
X1918210Y882245D01*
X1917793Y881411D01*
X1917502Y881036D01*
X1917085Y880786D01*
X1916710Y880703D01*
Y882453D01*
G01Y884595D02*
X1917252Y884678D01*
X1917710Y884803D01*
X1918127Y884970D01*
X1918585Y885178D01*
X1919210Y885511D01*
Y883845D01*
G01X1916710Y887778D02*
X1919210D01*
X1918710Y887278D01*
G01X1916710D02*
Y888278D01*
G01X1924110Y874545D02*
X1926610D01*
Y875586D01*
X1926485Y875920D01*
X1926318Y876128D01*
X1925985Y876211D01*
X1925652Y876128D01*
X1925443Y875878D01*
X1925318Y875586D01*
Y874545D01*
G01Y875586D02*
X1924110Y876211D01*
G01Y878478D02*
X1926610D01*
X1926110Y877978D01*
G01X1924110D02*
Y878978D01*
G01X1926193Y880786D02*
X1926443Y881036D01*
X1926568Y881328D01*
X1926610Y881661D01*
X1926527Y882078D01*
X1926318Y882370D01*
X1926068Y882453D01*
X1925818Y882411D01*
X1925610Y882245D01*
X1925193Y881411D01*
X1924902Y881036D01*
X1924485Y880786D01*
X1924110Y880703D01*
Y882453D01*
G01Y884595D02*
X1924652Y884678D01*
X1925110Y884803D01*
X1925527Y884970D01*
X1925985Y885178D01*
X1926610Y885511D01*
Y883845D01*
G01X1924402Y887070D02*
X1924193Y887361D01*
X1924110Y887695D01*
X1924193Y888028D01*
X1924443Y888320D01*
X1924818Y888528D01*
X1925193Y888611D01*
X1925652D01*
X1926027Y888528D01*
X1926360Y888320D01*
X1926527Y888070D01*
X1926610Y887778D01*
X1926527Y887445D01*
X1926360Y887195D01*
X1926110Y887028D01*
X1925777Y886945D01*
X1925485Y887028D01*
X1925193Y887236D01*
X1925027Y887486D01*
X1924985Y887778D01*
X1925068Y888111D01*
X1925277Y888361D01*
X1925652Y888611D01*
G01X1922910Y875378D02*
X1920410D01*
G01X1922910Y874420D02*
Y876336D01*
G01X1920410Y877645D02*
X1922910D01*
Y878645D01*
X1922785Y878978D01*
X1922493Y879228D01*
X1922160Y879311D01*
X1921827Y879228D01*
X1921577Y879020D01*
X1921452Y878645D01*
Y877645D01*
G01X1922493Y880786D02*
X1922743Y881036D01*
X1922868Y881328D01*
X1922910Y881661D01*
X1922827Y882078D01*
X1922618Y882370D01*
X1922368Y882453D01*
X1922118Y882411D01*
X1921910Y882245D01*
X1921493Y881411D01*
X1921202Y881036D01*
X1920785Y880786D01*
X1920410Y880703D01*
Y882453D01*
G01X1920785Y883761D02*
X1920577Y884011D01*
X1920452Y884303D01*
X1920410Y884678D01*
X1920493Y885053D01*
X1920660Y885345D01*
X1920952Y885553D01*
X1921285Y885595D01*
X1921618Y885511D01*
X1921827Y885303D01*
X1921993Y885011D01*
X1922035Y884720D01*
X1921993Y884428D01*
X1921827Y884053D01*
X1922910Y884178D01*
Y885303D01*
G01X1920702Y887070D02*
X1920493Y887361D01*
X1920410Y887695D01*
X1920493Y888028D01*
X1920743Y888320D01*
X1921118Y888528D01*
X1921493Y888611D01*
X1921952D01*
X1922327Y888528D01*
X1922660Y888320D01*
X1922827Y888070D01*
X1922910Y887778D01*
X1922827Y887445D01*
X1922660Y887195D01*
X1922410Y887028D01*
X1922077Y886945D01*
X1921785Y887028D01*
X1921493Y887236D01*
X1921327Y887486D01*
X1921285Y887778D01*
X1921368Y888111D01*
X1921577Y888361D01*
X1921952Y888611D01*
G01X1912532Y912665D02*
X1915032D01*
Y913706D01*
X1914907Y914040D01*
X1914740Y914248D01*
X1914407Y914331D01*
X1914074Y914248D01*
X1913865Y913998D01*
X1913740Y913706D01*
Y912665D01*
G01Y913706D02*
X1912532Y914331D01*
G01Y916598D02*
X1915032D01*
X1914532Y916098D01*
G01X1912532D02*
Y917098D01*
G01X1914615Y918906D02*
X1914865Y919156D01*
X1914990Y919448D01*
X1915032Y919781D01*
X1914949Y920198D01*
X1914740Y920490D01*
X1914490Y920573D01*
X1914240Y920531D01*
X1914032Y920365D01*
X1913615Y919531D01*
X1913324Y919156D01*
X1912907Y918906D01*
X1912532Y918823D01*
Y920573D01*
G01Y922715D02*
X1913074Y922798D01*
X1913532Y922923D01*
X1913949Y923090D01*
X1914407Y923298D01*
X1915032Y923631D01*
Y921965D01*
G01X1912532Y926398D02*
X1915032D01*
X1913240Y924856D01*
Y926940D01*
G01X1920723Y891238D02*
X1923223D01*
Y892279D01*
X1923098Y892613D01*
X1922931Y892821D01*
X1922598Y892904D01*
X1922265Y892821D01*
X1922056Y892571D01*
X1921931Y892279D01*
Y891238D01*
G01Y892279D02*
X1920723Y892904D01*
G01Y895171D02*
X1923223D01*
X1922723Y894671D01*
G01X1920723D02*
Y895671D01*
G01X1922806Y897479D02*
X1923056Y897729D01*
X1923181Y898021D01*
X1923223Y898354D01*
X1923140Y898771D01*
X1922931Y899063D01*
X1922681Y899146D01*
X1922431Y899104D01*
X1922223Y898938D01*
X1921806Y898104D01*
X1921515Y897729D01*
X1921098Y897479D01*
X1920723Y897396D01*
Y899146D01*
G01X1921765Y900579D02*
X1922056Y900871D01*
X1922223Y901121D01*
X1922306Y901454D01*
X1922223Y901746D01*
X1922056Y901954D01*
X1921806Y902121D01*
X1921515Y902163D01*
X1921265Y902121D01*
X1921015Y901954D01*
X1920806Y901704D01*
X1920723Y901413D01*
X1920806Y901079D01*
X1921056Y900788D01*
X1921431Y900621D01*
X1921848Y900579D01*
X1922390Y900663D01*
X1922681Y900788D01*
X1922973Y900996D01*
X1923181Y901288D01*
X1923223Y901579D01*
X1923140Y901871D01*
X1922931Y902079D01*
G01X1922806Y903679D02*
X1923056Y903929D01*
X1923181Y904221D01*
X1923223Y904554D01*
X1923140Y904971D01*
X1922931Y905263D01*
X1922681Y905346D01*
X1922431Y905304D01*
X1922223Y905138D01*
X1921806Y904304D01*
X1921515Y903929D01*
X1921098Y903679D01*
X1920723Y903596D01*
Y905346D01*
G01X1924446Y891308D02*
X1926946D01*
Y892349D01*
X1926821Y892683D01*
X1926654Y892891D01*
X1926321Y892974D01*
X1925988Y892891D01*
X1925779Y892641D01*
X1925654Y892349D01*
Y891308D01*
G01Y892349D02*
X1924446Y892974D01*
G01Y895241D02*
X1926946D01*
X1926446Y894741D01*
G01X1924446D02*
Y895741D01*
G01X1926529Y897549D02*
X1926779Y897799D01*
X1926904Y898091D01*
X1926946Y898424D01*
X1926863Y898841D01*
X1926654Y899133D01*
X1926404Y899216D01*
X1926154Y899174D01*
X1925946Y899008D01*
X1925529Y898174D01*
X1925238Y897799D01*
X1924821Y897549D01*
X1924446Y897466D01*
Y899216D01*
G01X1925488Y900649D02*
X1925779Y900941D01*
X1925946Y901191D01*
X1926029Y901524D01*
X1925946Y901816D01*
X1925779Y902024D01*
X1925529Y902191D01*
X1925238Y902233D01*
X1924988Y902191D01*
X1924738Y902024D01*
X1924529Y901774D01*
X1924446Y901483D01*
X1924529Y901149D01*
X1924779Y900858D01*
X1925154Y900691D01*
X1925571Y900649D01*
X1926113Y900733D01*
X1926404Y900858D01*
X1926696Y901066D01*
X1926904Y901358D01*
X1926946Y901649D01*
X1926863Y901941D01*
X1926654Y902149D01*
G01X1924946Y903624D02*
X1924654Y903874D01*
X1924488Y904208D01*
X1924446Y904583D01*
X1924488Y904916D01*
X1924696Y905249D01*
X1924946Y905458D01*
X1925196Y905499D01*
X1925488Y905416D01*
X1925696Y905124D01*
X1925779Y904833D01*
Y904458D01*
G01Y904833D02*
X1925904Y905083D01*
X1926113Y905291D01*
X1926363Y905374D01*
X1926613Y905291D01*
X1926821Y905083D01*
X1926946Y904708D01*
X1926904Y904333D01*
X1926738Y903958D01*
G01X1917023Y891238D02*
X1919523D01*
Y892279D01*
X1919398Y892613D01*
X1919231Y892821D01*
X1918898Y892904D01*
X1918565Y892821D01*
X1918356Y892571D01*
X1918231Y892279D01*
Y891238D01*
G01Y892279D02*
X1917023Y892904D01*
G01Y895171D02*
X1919523D01*
X1919023Y894671D01*
G01X1917023D02*
Y895671D01*
G01X1919106Y897479D02*
X1919356Y897729D01*
X1919481Y898021D01*
X1919523Y898354D01*
X1919440Y898771D01*
X1919231Y899063D01*
X1918981Y899146D01*
X1918731Y899104D01*
X1918523Y898938D01*
X1918106Y898104D01*
X1917815Y897729D01*
X1917398Y897479D01*
X1917023Y897396D01*
Y899146D01*
G01X1918065Y900579D02*
X1918356Y900871D01*
X1918523Y901121D01*
X1918606Y901454D01*
X1918523Y901746D01*
X1918356Y901954D01*
X1918106Y902121D01*
X1917815Y902163D01*
X1917565Y902121D01*
X1917315Y901954D01*
X1917106Y901704D01*
X1917023Y901413D01*
X1917106Y901079D01*
X1917356Y900788D01*
X1917731Y900621D01*
X1918148Y900579D01*
X1918690Y900663D01*
X1918981Y900788D01*
X1919273Y900996D01*
X1919481Y901288D01*
X1919523Y901579D01*
X1919440Y901871D01*
X1919231Y902079D01*
G01X1917398Y903554D02*
X1917190Y903804D01*
X1917065Y904096D01*
X1917023Y904471D01*
X1917106Y904846D01*
X1917273Y905138D01*
X1917565Y905346D01*
X1917898Y905388D01*
X1918231Y905304D01*
X1918440Y905096D01*
X1918606Y904804D01*
X1918648Y904513D01*
X1918606Y904221D01*
X1918440Y903846D01*
X1919523Y903971D01*
Y905096D01*
G01X1925055Y907583D02*
Y910083D01*
X1924014D01*
X1923680Y909958D01*
X1923472Y909791D01*
X1923389Y909458D01*
X1923472Y909125D01*
X1923722Y908916D01*
X1924014Y908791D01*
X1925055D01*
G01X1924014D02*
X1923389Y907583D01*
G01X1921122D02*
Y910083D01*
X1921622Y909583D01*
G01Y907583D02*
X1920622D01*
G01X1918814Y909666D02*
X1918564Y909916D01*
X1918272Y910041D01*
X1917939Y910083D01*
X1917522Y910000D01*
X1917230Y909791D01*
X1917147Y909541D01*
X1917189Y909291D01*
X1917355Y909083D01*
X1918189Y908666D01*
X1918564Y908375D01*
X1918814Y907958D01*
X1918897Y907583D01*
X1917147D01*
G01X1915005D02*
X1914922Y908125D01*
X1914797Y908583D01*
X1914630Y909000D01*
X1914422Y909458D01*
X1914089Y910083D01*
X1915755D01*
G01X1912739Y908083D02*
X1912489Y907791D01*
X1912155Y907625D01*
X1911780Y907583D01*
X1911447Y907625D01*
X1911114Y907833D01*
X1910905Y908083D01*
X1910864Y908333D01*
X1910947Y908625D01*
X1911239Y908833D01*
X1911530Y908916D01*
X1911905D01*
G01X1911530D02*
X1911280Y909041D01*
X1911072Y909250D01*
X1910989Y909500D01*
X1911072Y909750D01*
X1911280Y909958D01*
X1911655Y910083D01*
X1912030Y910041D01*
X1912405Y909875D01*
G01X1915615Y892988D02*
X1915740Y892738D01*
X1915823Y892446D01*
Y892113D01*
X1915698Y891738D01*
X1915490Y891446D01*
X1915240Y891238D01*
X1914823Y891071D01*
X1914448Y891029D01*
X1914073Y891113D01*
X1913823Y891238D01*
X1913573Y891488D01*
X1913406Y891779D01*
X1913323Y892071D01*
Y892363D01*
X1913406Y892654D01*
X1913531Y892904D01*
X1913698Y893113D01*
G01X1914365Y894379D02*
X1914656Y894671D01*
X1914823Y894921D01*
X1914906Y895254D01*
X1914823Y895546D01*
X1914656Y895754D01*
X1914406Y895921D01*
X1914115Y895963D01*
X1913865Y895921D01*
X1913615Y895754D01*
X1913406Y895504D01*
X1913323Y895213D01*
X1913406Y894879D01*
X1913656Y894588D01*
X1914031Y894421D01*
X1914448Y894379D01*
X1914990Y894463D01*
X1915281Y894588D01*
X1915573Y894796D01*
X1915781Y895088D01*
X1915823Y895379D01*
X1915740Y895671D01*
X1915531Y895879D01*
G01X1913698Y897354D02*
X1913490Y897604D01*
X1913365Y897896D01*
X1913323Y898271D01*
X1913406Y898646D01*
X1913573Y898938D01*
X1913865Y899146D01*
X1914198Y899188D01*
X1914531Y899104D01*
X1914740Y898896D01*
X1914906Y898604D01*
X1914948Y898313D01*
X1914906Y898021D01*
X1914740Y897646D01*
X1915823Y897771D01*
Y898896D01*
G01X1913323Y901871D02*
X1915823D01*
X1914031Y900329D01*
Y902413D01*
G01X1918524Y914415D02*
X1918649Y914165D01*
X1918732Y913873D01*
Y913540D01*
X1918607Y913165D01*
X1918399Y912873D01*
X1918149Y912665D01*
X1917732Y912498D01*
X1917357Y912456D01*
X1916982Y912540D01*
X1916732Y912665D01*
X1916482Y912915D01*
X1916315Y913206D01*
X1916232Y913498D01*
Y913790D01*
X1916315Y914081D01*
X1916440Y914331D01*
X1916607Y914540D01*
G01X1917274Y915806D02*
X1917565Y916098D01*
X1917732Y916348D01*
X1917815Y916681D01*
X1917732Y916973D01*
X1917565Y917181D01*
X1917315Y917348D01*
X1917024Y917390D01*
X1916774Y917348D01*
X1916524Y917181D01*
X1916315Y916931D01*
X1916232Y916640D01*
X1916315Y916306D01*
X1916565Y916015D01*
X1916940Y915848D01*
X1917357Y915806D01*
X1917899Y915890D01*
X1918190Y916015D01*
X1918482Y916223D01*
X1918690Y916515D01*
X1918732Y916806D01*
X1918649Y917098D01*
X1918440Y917306D01*
G01X1917274Y918906D02*
X1917565Y919198D01*
X1917732Y919448D01*
X1917815Y919781D01*
X1917732Y920073D01*
X1917565Y920281D01*
X1917315Y920448D01*
X1917024Y920490D01*
X1916774Y920448D01*
X1916524Y920281D01*
X1916315Y920031D01*
X1916232Y919740D01*
X1916315Y919406D01*
X1916565Y919115D01*
X1916940Y918948D01*
X1917357Y918906D01*
X1917899Y918990D01*
X1918190Y919115D01*
X1918482Y919323D01*
X1918690Y919615D01*
X1918732Y919906D01*
X1918649Y920198D01*
X1918440Y920406D01*
G01X1916232Y922798D02*
X1916274Y923090D01*
X1916399Y923423D01*
X1916607Y923631D01*
X1916899Y923715D01*
X1917190Y923631D01*
X1917440Y923381D01*
X1917565Y923006D01*
Y922590D01*
X1917649Y922340D01*
X1917857Y922131D01*
X1918149Y922048D01*
X1918440Y922173D01*
X1918649Y922465D01*
X1918732Y922798D01*
X1918649Y923131D01*
X1918440Y923423D01*
X1918149Y923548D01*
X1917857Y923465D01*
X1917649Y923256D01*
X1917565Y923006D01*
Y922590D01*
X1917440Y922215D01*
X1917190Y921965D01*
X1916899Y921881D01*
X1916607Y921965D01*
X1916399Y922173D01*
X1916274Y922506D01*
X1916232Y922798D01*
G54D16*
G01X64263Y984325D02*
X65363D01*
G01X61563D02*
X62663D01*
G01X93593Y979195D02*
Y983195D01*
G01X130563Y557725D02*
X131663D01*
G01X127863D02*
X128963D01*
G01X160293Y567195D02*
Y571195D01*
G01X137826Y998541D02*
Y999641D01*
G01Y995841D02*
Y996941D01*
G01X158941Y995644D02*
X154941D01*
G01X204526Y586541D02*
Y587641D01*
G01Y583841D02*
Y584941D01*
G01X225641Y583644D02*
X221641D01*
G01X731582Y865626D02*
X735582D01*
G01X744183Y908689D02*
X748183D01*
G01X749183Y918289D02*
Y922289D01*
G01X716552Y890520D02*
X720552D01*
G01X757104Y865773D02*
Y866873D01*
G01Y863073D02*
Y864173D01*
G01X755917Y879689D02*
X754817D01*
G01X758617D02*
X757517D01*
G01X749711Y879717D02*
X753711D01*
G01X1703561Y1006847D02*
X1704661D01*
G01X1700861D02*
X1701961D01*
G01X1733711Y1000024D02*
Y1004024D01*
G01X1779626Y1010541D02*
Y1011641D01*
G01Y1007841D02*
Y1008941D01*
G01X1800741Y1007644D02*
X1796741D01*
G01X1833066Y907099D02*
Y905999D01*
G01Y909799D02*
Y908699D01*
G01X1859000Y964200D02*
Y963100D01*
G01Y966900D02*
Y965800D01*
G01X1884720Y872918D02*
Y876918D01*
G01X1904959Y906550D02*
Y907650D01*
G01Y903850D02*
Y904950D01*
G01X1886000Y898000D02*
X1890000D01*
G01X1874271Y939766D02*
X1878271D01*
M02*
